(lib_symbols
	(symbol "antmicroCapacitors0402:C_100n_0402" (pin_numbers hide) (pin_names hide) (in_bom yes) (on_board yes)
      (property "Reference" "C" (at 20.32 -5.08 0)
        (effects (font (size 1.27 1.27) (thickness 0.15)) (justify left bottom))
      )
      (property "Value" "C_100n_0402" (at 20.32 -10.16 0)
        (effects (font (size 1.27 1.27) (thickness 0.15)) (justify left bottom) hide)
      )
      (property "Footprint" "antmicro-footprints:C_0402_1005Metric" (at 20.32 -12.7 0)
        (effects (font (size 1.27 1.27) (thickness 0.15)) (justify left bottom) hide)
      )
      (property "Datasheet" "https://www.murata.com/products/productdetail?partno=GRM155R61H104KE14%23" (at 20.32 -15.24 0)
        (effects (font (size 1.27 1.27) (thickness 0.15)) (justify left bottom) hide)
      )
      (property "MPN" "GRM155R61H104KE14D" (at 20.32 -17.78 0)
        (effects (font (size 1.27 1.27) (thickness 0.15)) (justify left bottom) hide)
      )
      (property "Manufacturer" "Murata" (at 20.32 -20.32 0)
        (effects (font (size 1.27 1.27) (thickness 0.15)) (justify left bottom) hide)
      )
      (property "License" "Apache-2.0" (at 20.32 -22.86 0)
        (effects (font (size 1.27 1.27) (thickness 0.15)) (justify left bottom) hide)
      )
      (property "Author" "Antmicro" (at 20.32 -25.4 0)
        (effects (font (size 1.27 1.27) (thickness 0.15)) (justify left bottom) hide)
      )
      (property "Val" "100n" (at 20.32 -7.62 0)
        (effects (font (size 1.27 1.27) (thickness 0.15)) (justify left bottom))
      )
      (property "Voltage" "50V" (at 20.32 -27.94 0)
        (effects (font (size 1.27 1.27)) (justify left bottom) hide)
      )
      (property "Dielectric" "X5R" (at 20.32 -30.48 0)
        (effects (font (size 1.27 1.27)) (justify left bottom) hide)
      )
      (property "Public" "False" (at 20.32 -33.02 0)
        (effects (font (size 1.27 1.27)) (justify left bottom) hide)
      )
      (property "ki_keywords" "0402, SMT, CAPACITOR, PASSIVE, CERAMIC, MLCC" (at 0 0 0)
        (effects (font (size 1.27 1.27)) hide)
      )
      (property "ki_description" "SMD Multilayer Ceramic Capacitor, 0.1 µF, 50 V, 0402 [1005 Metric], ± 10%, X5R, GRM Series" (at 0 0 0)
        (effects (font (size 1.27 1.27)) hide)
      )
      (symbol "C_100n_0402_0_1"
        (polyline
          (pts
            (xy 2.032 -1.524)
            (xy 2.032 1.524)
          )
          (stroke (width 0.3048) (type default))
          (fill (type none))
        )
        (polyline
          (pts
            (xy 3.048 -1.524)
            (xy 3.048 1.524)
          )
          (stroke (width 0.3302) (type default))
          (fill (type none))
        )
      )
      (symbol "C_100n_0402_1_1"
        (pin passive line (at 0 0 0) (length 2.032)
          (name "~" (effects (font (size 1.27 1.27))))
          (number "1" (effects (font (size 1.27 1.27))))
        )
        (pin passive line (at 5.08 0 180) (length 2.032)
          (name "~" (effects (font (size 1.27 1.27))))
          (number "2" (effects (font (size 1.27 1.27))))
        )
      )
    )
	(symbol "antmicroCapacitors0402:C_470p_0402" (pin_numbers hide) (pin_names hide) (in_bom yes) (on_board yes)
      (property "Reference" "C" (at 20.32 -5.08 0)
        (effects (font (size 1.27 1.27) (thickness 0.15)) (justify left bottom))
      )
      (property "Value" "C_470p_0402" (at 20.32 -10.16 0)
        (effects (font (size 1.27 1.27) (thickness 0.15)) (justify left bottom) hide)
      )
      (property "Footprint" "antmicro-footprints:C_0402_1005Metric" (at 20.32 -12.7 0)
        (effects (font (size 1.27 1.27) (thickness 0.15)) (justify left bottom) hide)
      )
      (property "Datasheet" "https://www.passivecomponent.com/wp-content/uploads/datasheet/WTC_MLCC_General_Purpose.pdf" (at 20.32 -15.24 0)
        (effects (font (size 1.27 1.27) (thickness 0.15)) (justify left bottom) hide)
      )
      (property "MPN" "0402B471K250CT" (at 20.32 -17.78 0)
        (effects (font (size 1.27 1.27) (thickness 0.15)) (justify left bottom) hide)
      )
      (property "Manufacturer" "Walsin" (at 20.32 -20.32 0)
        (effects (font (size 1.27 1.27) (thickness 0.15)) (justify left bottom) hide)
      )
      (property "License" "Apache-2.0" (at 20.32 -22.86 0)
        (effects (font (size 1.27 1.27) (thickness 0.15)) (justify left bottom) hide)
      )
      (property "Author" "Antmicro" (at 20.32 -25.4 0)
        (effects (font (size 1.27 1.27) (thickness 0.15)) (justify left bottom) hide)
      )
      (property "Val" "470p" (at 20.32 -7.62 0)
        (effects (font (size 1.27 1.27) (thickness 0.15)) (justify left bottom))
      )
      (property "Voltage" "" (at 20.32 -27.94 0)
        (effects (font (size 1.27 1.27)) (justify left bottom) hide)
      )
      (property "Dielectric" "" (at 20.32 -30.48 0)
        (effects (font (size 1.27 1.27)) (justify left bottom) hide)
      )
      (property "Public" "False" (at 20.32 -33.02 0)
        (effects (font (size 1.27 1.27)) (justify left bottom) hide)
      )
      (property "ki_keywords" "0402, SMT, CAPACITOR, PASSIVE, MLCC" (at 0 0 0)
        (effects (font (size 1.27 1.27)) hide)
      )
      (property "ki_description" "SMD Multilayer Ceramic Capacitor, General Purpose, 470 pF, 25 V, 0402 [1005 Metric], ± 10%, X7R" (at 0 0 0)
        (effects (font (size 1.27 1.27)) hide)
      )
      (symbol "C_470p_0402_0_1"
        (polyline
          (pts
            (xy 2.032 -1.524)
            (xy 2.032 1.524)
          )
          (stroke (width 0.3048) (type default))
          (fill (type none))
        )
        (polyline
          (pts
            (xy 3.048 -1.524)
            (xy 3.048 1.524)
          )
          (stroke (width 0.3302) (type default))
          (fill (type none))
        )
      )
      (symbol "C_470p_0402_1_1"
        (pin passive line (at 0 0 0) (length 2.032)
          (name "~" (effects (font (size 1.27 1.27))))
          (number "1" (effects (font (size 1.27 1.27))))
        )
        (pin passive line (at 5.08 0 180) (length 2.032)
          (name "~" (effects (font (size 1.27 1.27))))
          (number "2" (effects (font (size 1.27 1.27))))
        )
      )
    )
	(symbol "antmicroCapacitors0402:C_47p_0402" (pin_numbers hide) (pin_names hide) (in_bom yes) (on_board yes)
      (property "Reference" "C" (at 20.32 -5.08 0)
        (effects (font (size 1.27 1.27) (thickness 0.15)) (justify left bottom))
      )
      (property "Value" "C_47p_0402" (at 20.32 -10.16 0)
        (effects (font (size 1.27 1.27) (thickness 0.15)) (justify left bottom) hide)
      )
      (property "Footprint" "antmicro-footprints:C_0402_1005Metric" (at 20.32 -12.7 0)
        (effects (font (size 1.27 1.27) (thickness 0.15)) (justify left bottom) hide)
      )
      (property "Datasheet" "https://www.kemet.com/en/us/capacitors/product/C0402C470J5GACTU.html" (at 20.32 -15.24 0)
        (effects (font (size 1.27 1.27) (thickness 0.15)) (justify left bottom) hide)
      )
      (property "MPN" "C0402C470J5GACTU" (at 20.32 -17.78 0)
        (effects (font (size 1.27 1.27) (thickness 0.15)) (justify left bottom) hide)
      )
      (property "Manufacturer" "KEMET" (at 20.32 -20.32 0)
        (effects (font (size 1.27 1.27) (thickness 0.15)) (justify left bottom) hide)
      )
      (property "License" "Apache-2.0" (at 20.32 -22.86 0)
        (effects (font (size 1.27 1.27) (thickness 0.15)) (justify left bottom) hide)
      )
      (property "Author" "Antmicro" (at 20.32 -25.4 0)
        (effects (font (size 1.27 1.27) (thickness 0.15)) (justify left bottom) hide)
      )
      (property "Val" "47p" (at 20.32 -7.62 0)
        (effects (font (size 1.27 1.27) (thickness 0.15)) (justify left bottom))
      )
      (property "Voltage" "" (at 20.32 -27.94 0)
        (effects (font (size 1.27 1.27)) (justify left bottom) hide)
      )
      (property "Dielectric" "C0G" (at 20.32 -30.48 0)
        (effects (font (size 1.27 1.27)) (justify left bottom) hide)
      )
      (property "Public" "False" (at 20.32 -33.02 0)
        (effects (font (size 1.27 1.27)) (justify left bottom) hide)
      )
      (property "ki_keywords" "0402, SMT, CAPACITOR, PASSIVE, CERAMIC, MLCC" (at 0 0 0)
        (effects (font (size 1.27 1.27)) hide)
      )
      (property "ki_description" "SMD Multilayer Ceramic Capacitor, 47 pF, 50 V, 0402 [1005 Metric], ± 5%, C0G / NP0, C Series KEMET" (at 0 0 0)
        (effects (font (size 1.27 1.27)) hide)
      )
      (symbol "C_47p_0402_0_1"
        (polyline
          (pts
            (xy 2.032 -1.524)
            (xy 2.032 1.524)
          )
          (stroke (width 0.3048) (type default))
          (fill (type none))
        )
        (polyline
          (pts
            (xy 3.048 -1.524)
            (xy 3.048 1.524)
          )
          (stroke (width 0.3302) (type default))
          (fill (type none))
        )
      )
      (symbol "C_47p_0402_1_1"
        (pin passive line (at 0 0 0) (length 2.032)
          (name "~" (effects (font (size 1.27 1.27))))
          (number "1" (effects (font (size 1.27 1.27))))
        )
        (pin passive line (at 5.08 0 180) (length 2.032)
          (name "~" (effects (font (size 1.27 1.27))))
          (number "2" (effects (font (size 1.27 1.27))))
        )
      )
    )
	(symbol "antmicroCapacitors0603:C_10u_0603" (pin_numbers hide) (pin_names hide) (in_bom yes) (on_board yes)
      (property "Reference" "C" (at 20.32 -5.08 0)
        (effects (font (size 1.27 1.27) (thickness 0.15)) (justify left bottom))
      )
      (property "Value" "C_10u_0603" (at 20.32 -10.16 0)
        (effects (font (size 1.27 1.27) (thickness 0.15)) (justify left bottom) hide)
      )
      (property "Footprint" "antmicro-footprints:C_0603_1608Metric" (at 20.32 -12.7 0)
        (effects (font (size 1.27 1.27) (thickness 0.15)) (justify left bottom) hide)
      )
      (property "Datasheet" "https://www.murata.com/products/productdetail?partno=GRM188R61A106KE69%23" (at 20.32 -15.24 0)
        (effects (font (size 1.27 1.27) (thickness 0.15)) (justify left bottom) hide)
      )
      (property "MPN" "GRM188R61A106KE69D" (at 20.32 -17.78 0)
        (effects (font (size 1.27 1.27) (thickness 0.15)) (justify left bottom) hide)
      )
      (property "Manufacturer" "Murata" (at 20.32 -20.32 0)
        (effects (font (size 1.27 1.27) (thickness 0.15)) (justify left bottom) hide)
      )
      (property "License" "Apache-2.0" (at 20.32 -22.86 0)
        (effects (font (size 1.27 1.27) (thickness 0.15)) (justify left bottom) hide)
      )
      (property "Author" "Antmicro" (at 20.32 -25.4 0)
        (effects (font (size 1.27 1.27) (thickness 0.15)) (justify left bottom) hide)
      )
      (property "Val" "10u" (at 20.32 -7.62 0)
        (effects (font (size 1.27 1.27) (thickness 0.15)) (justify left bottom))
      )
      (property "Voltage" "" (at 20.32 -27.94 0)
        (effects (font (size 1.27 1.27)) (justify left bottom) hide)
      )
      (property "Dielectric" "template_dielectric" (at 20.32 -30.48 0)
        (effects (font (size 1.27 1.27)) (justify left bottom) hide)
      )
      (property "Public" "False" (at 20.32 -33.02 0)
        (effects (font (size 1.27 1.27)) (justify left bottom) hide)
      )
      (property "ki_keywords" "0603, SMT, CAPACITOR, PASSIVE, CERAMIC, MLCC" (at 0 0 0)
        (effects (font (size 1.27 1.27)) hide)
      )
      (property "ki_description" "SMD Multilayer Ceramic Capacitor, 10 µF, 10 V, 0603 [1608 Metric], ± 10%, X5R, GRM Series" (at 0 0 0)
        (effects (font (size 1.27 1.27)) hide)
      )
      (symbol "C_10u_0603_0_1"
        (polyline
          (pts
            (xy 2.032 -1.524)
            (xy 2.032 1.524)
          )
          (stroke (width 0.3048) (type default))
          (fill (type none))
        )
        (polyline
          (pts
            (xy 3.048 -1.524)
            (xy 3.048 1.524)
          )
          (stroke (width 0.3302) (type default))
          (fill (type none))
        )
      )
      (symbol "C_10u_0603_1_1"
        (pin passive line (at 0 0 0) (length 2.032)
          (name "~" (effects (font (size 1.27 1.27))))
          (number "1" (effects (font (size 1.27 1.27))))
        )
        (pin passive line (at 5.08 0 180) (length 2.032)
          (name "~" (effects (font (size 1.27 1.27))))
          (number "2" (effects (font (size 1.27 1.27))))
        )
      )
    )
	(symbol "antmicroCapacitors0603:C_4u7_0603" (pin_numbers hide) (pin_names hide) (in_bom yes) (on_board yes)
      (property "Reference" "C" (at 20.32 -5.08 0)
        (effects (font (size 1.27 1.27) (thickness 0.15)) (justify left bottom))
      )
      (property "Value" "C_4u7_0603" (at 20.32 -10.16 0)
        (effects (font (size 1.27 1.27) (thickness 0.15)) (justify left bottom) hide)
      )
      (property "Footprint" "antmicro-footprints:C_0603_1608Metric" (at 20.32 -12.7 0)
        (effects (font (size 1.27 1.27) (thickness 0.15)) (justify left bottom) hide)
      )
      (property "Datasheet" "https://product.tdk.com/en/search/capacitor/ceramic/mlcc/info?part_no=C1608X5R1V475M080AC" (at 20.32 -15.24 0)
        (effects (font (size 1.27 1.27) (thickness 0.15)) (justify left bottom) hide)
      )
      (property "MPN" "C1608X5R1V475M080AC" (at 20.32 -17.78 0)
        (effects (font (size 1.27 1.27) (thickness 0.15)) (justify left bottom) hide)
      )
      (property "Manufacturer" "TDK" (at 20.32 -20.32 0)
        (effects (font (size 1.27 1.27) (thickness 0.15)) (justify left bottom) hide)
      )
      (property "License" "Apache-2.0" (at 20.32 -22.86 0)
        (effects (font (size 1.27 1.27) (thickness 0.15)) (justify left bottom) hide)
      )
      (property "Author" "Antmicro" (at 20.32 -25.4 0)
        (effects (font (size 1.27 1.27) (thickness 0.15)) (justify left bottom) hide)
      )
      (property "Val" "4u7" (at 20.32 -7.62 0)
        (effects (font (size 1.27 1.27) (thickness 0.15)) (justify left bottom))
      )
      (property "Voltage" "" (at 20.32 -27.94 0)
        (effects (font (size 1.27 1.27)) (justify left bottom) hide)
      )
      (property "Dielectric" "" (at 20.32 -30.48 0)
        (effects (font (size 1.27 1.27)) (justify left bottom) hide)
      )
      (property "Public" "False" (at 20.32 -33.02 0)
        (effects (font (size 1.27 1.27)) (justify left bottom) hide)
      )
      (property "ki_keywords" "0603, SMT, CAPACITOR, PASSIVE, CERAMIC, MLCC" (at 0 0 0)
        (effects (font (size 1.27 1.27)) hide)
      )
      (property "ki_description" "SMD Multilayer Ceramic Capacitor, 4.7 µF, 35 V, 0603 [1608 Metric], ± 20%, X5R, C" (at 0 0 0)
        (effects (font (size 1.27 1.27)) hide)
      )
      (symbol "C_4u7_0603_0_1"
        (polyline
          (pts
            (xy 2.032 -1.524)
            (xy 2.032 1.524)
          )
          (stroke (width 0.3048) (type default))
          (fill (type none))
        )
        (polyline
          (pts
            (xy 3.048 -1.524)
            (xy 3.048 1.524)
          )
          (stroke (width 0.3302) (type default))
          (fill (type none))
        )
      )
      (symbol "C_4u7_0603_1_1"
        (pin passive line (at 0 0 0) (length 2.032)
          (name "~" (effects (font (size 1.27 1.27))))
          (number "1" (effects (font (size 1.27 1.27))))
        )
        (pin passive line (at 5.08 0 180) (length 2.032)
          (name "~" (effects (font (size 1.27 1.27))))
          (number "2" (effects (font (size 1.27 1.27))))
        )
      )
    )
	(symbol "antmicroFCCConnectors:5051101992" (in_bom yes) (on_board yes)
      (property "Reference" "J" (at 22.86 -5.08 0)
        (effects (font (size 1.27 1.27) (thickness 0.15)) (justify left bottom))
      )
      (property "Value" "5051101992" (at 22.86 -7.62 0)
        (effects (font (size 1.27 1.27) (thickness 0.15)) (justify left bottom) hide)
      )
      (property "Footprint" "antmicro-footprints:5051101992" (at 22.86 -10.16 0)
        (effects (font (size 1.27 1.27) (thickness 0.15)) (justify left bottom) hide)
      )
      (property "Datasheet" "https://www.molex.com/webdocs/datasheets/pdf/en-us/5051101992_FFC_FPC_CONNECTORS.pdf" (at 22.86 -12.7 0)
        (effects (font (size 1.27 1.27) (thickness 0.15)) (justify left bottom) hide)
      )
      (property "Manufacturer" "Molex" (at 22.86 -15.24 0)
        (effects (font (size 1.27 1.27) (thickness 0.15)) (justify left bottom) hide)
      )
      (property "MPN" "5051101992" (at 22.86 -17.78 0)
        (effects (font (size 1.27 1.27) (thickness 0.15)) (justify left bottom))
      )
      (property "Author" "Antmicro" (at 22.86 -20.32 0)
        (effects (font (size 1.27 1.27) (thickness 0.15)) (justify left bottom) hide)
      )
      (property "License" "Apache-2.0" (at 22.86 -22.86 0)
        (effects (font (size 1.27 1.27) (thickness 0.15)) (justify left bottom) hide)
      )
      (property "ki_keywords" "CONNECTOR" (at 0 0 0)
        (effects (font (size 1.27 1.27)) hide)
      )
      (property "ki_description" "FFC / FPC Board Connector, ZIF, 0.5 mm, 19 Contacts, Receptacle, Easy-On 505110, Surface Mount" (at 0 0 0)
        (effects (font (size 1.27 1.27)) hide)
      )
      (symbol "5051101992_1_1"
        (rectangle (start 2.54 2.54) (end 7.62 -48.26)
          (stroke (width 0.254) (type default))
          (fill (type background))
        )
        (pin passive line (at 0 0 0) (length 2.54)
          (name "1" (effects (font (size 1.27 1.27))))
          (number "1" (effects (font (size 1.27 1.27))))
        )
        (pin passive line (at 0 -22.86 0) (length 2.54)
          (name "10" (effects (font (size 1.27 1.27))))
          (number "10" (effects (font (size 1.27 1.27))))
        )
        (pin passive line (at 0 -25.4 0) (length 2.54)
          (name "11" (effects (font (size 1.27 1.27))))
          (number "11" (effects (font (size 1.27 1.27))))
        )
        (pin passive line (at 0 -27.94 0) (length 2.54)
          (name "12" (effects (font (size 1.27 1.27))))
          (number "12" (effects (font (size 1.27 1.27))))
        )
        (pin passive line (at 0 -30.48 0) (length 2.54)
          (name "13" (effects (font (size 1.27 1.27))))
          (number "13" (effects (font (size 1.27 1.27))))
        )
        (pin passive line (at 0 -33.02 0) (length 2.54)
          (name "14" (effects (font (size 1.27 1.27))))
          (number "14" (effects (font (size 1.27 1.27))))
        )
        (pin passive line (at 0 -35.56 0) (length 2.54)
          (name "15" (effects (font (size 1.27 1.27))))
          (number "15" (effects (font (size 1.27 1.27))))
        )
        (pin passive line (at 0 -38.1 0) (length 2.54)
          (name "16" (effects (font (size 1.27 1.27))))
          (number "16" (effects (font (size 1.27 1.27))))
        )
        (pin passive line (at 0 -40.64 0) (length 2.54)
          (name "17" (effects (font (size 1.27 1.27))))
          (number "17" (effects (font (size 1.27 1.27))))
        )
        (pin passive line (at 0 -43.18 0) (length 2.54)
          (name "18" (effects (font (size 1.27 1.27))))
          (number "18" (effects (font (size 1.27 1.27))))
        )
        (pin passive line (at 0 -45.72 0) (length 2.54)
          (name "19" (effects (font (size 1.27 1.27))))
          (number "19" (effects (font (size 1.27 1.27))))
        )
        (pin passive line (at 0 -2.54 0) (length 2.54)
          (name "2" (effects (font (size 1.27 1.27))))
          (number "2" (effects (font (size 1.27 1.27))))
        )
        (pin passive line (at 0 -5.08 0) (length 2.54)
          (name "3" (effects (font (size 1.27 1.27))))
          (number "3" (effects (font (size 1.27 1.27))))
        )
        (pin passive line (at 0 -7.62 0) (length 2.54)
          (name "4" (effects (font (size 1.27 1.27))))
          (number "4" (effects (font (size 1.27 1.27))))
        )
        (pin passive line (at 0 -10.16 0) (length 2.54)
          (name "5" (effects (font (size 1.27 1.27))))
          (number "5" (effects (font (size 1.27 1.27))))
        )
        (pin passive line (at 0 -12.7 0) (length 2.54)
          (name "6" (effects (font (size 1.27 1.27))))
          (number "6" (effects (font (size 1.27 1.27))))
        )
        (pin passive line (at 0 -15.24 0) (length 2.54)
          (name "7" (effects (font (size 1.27 1.27))))
          (number "7" (effects (font (size 1.27 1.27))))
        )
        (pin passive line (at 0 -17.78 0) (length 2.54)
          (name "8" (effects (font (size 1.27 1.27))))
          (number "8" (effects (font (size 1.27 1.27))))
        )
        (pin passive line (at 0 -20.32 0) (length 2.54)
          (name "9" (effects (font (size 1.27 1.27))))
          (number "9" (effects (font (size 1.27 1.27))))
        )
      )
    )
	(symbol "antmicroFCCConnectors:Conn_FFC_WE_68715014022" (in_bom yes) (on_board yes)
      (property "Reference" "J" (at 19.05 -5.08 0)
        (effects (font (size 1.27 1.27) (thickness 0.15)) (justify left bottom))
      )
      (property "Value" "Conn_FFC_WE_68715014022" (at 19.05 -7.62 0)
        (effects (font (size 1.27 1.27) (thickness 0.15)) (justify left bottom) hide)
      )
      (property "Footprint" "antmicro-footprints:Conn_FFC_WE_68715014x22" (at 19.05 -10.16 0)
        (effects (font (size 1.27 1.27) (thickness 0.15)) (justify left bottom) hide)
      )
      (property "Datasheet" "https://www.we-online.com/components/products/datasheet/68715014022.pdf" (at 19.05 -12.7 0)
        (effects (font (size 1.27 1.27) (thickness 0.15)) (justify left bottom) hide)
      )
      (property "MPN" "68715014022" (at 19.05 -15.24 0)
        (effects (font (size 1.27 1.27) (thickness 0.15)) (justify left bottom))
      )
      (property "Manufacturer" "Würth Elektronik" (at 19.05 -17.78 0)
        (effects (font (size 1.27 1.27) (thickness 0.15)) (justify left bottom) hide)
      )
      (property "Author" "Antmicro" (at 19.05 -20.32 0)
        (effects (font (size 1.27 1.27) (thickness 0.15)) (justify left bottom) hide)
      )
      (property "License" "Apache-2.0" (at 19.05 -22.86 0)
        (effects (font (size 1.27 1.27) (thickness 0.15)) (justify left bottom) hide)
      )
      (property "ki_keywords" "CONNECTOR" (at 0 0 0)
        (effects (font (size 1.27 1.27)) hide)
      )
      (property "ki_description" "FFC connector" (at 0 0 0)
        (effects (font (size 1.27 1.27)) hide)
      )
      (symbol "Conn_FFC_WE_68715014022_1_1"
        (rectangle (start 3.81 -124.333) (end 5.08 -124.587)
          (stroke (width 0.254) (type default))
          (fill (type background))
        )
        (rectangle (start 3.81 -121.793) (end 5.08 -122.047)
          (stroke (width 0.254) (type default))
          (fill (type background))
        )
        (rectangle (start 3.81 -119.253) (end 5.08 -119.507)
          (stroke (width 0.254) (type default))
          (fill (type background))
        )
        (rectangle (start 3.81 -116.713) (end 5.08 -116.967)
          (stroke (width 0.254) (type default))
          (fill (type background))
        )
        (rectangle (start 3.81 -114.173) (end 5.08 -114.427)
          (stroke (width 0.254) (type default))
          (fill (type background))
        )
        (rectangle (start 3.81 -111.633) (end 5.08 -111.887)
          (stroke (width 0.254) (type default))
          (fill (type background))
        )
        (rectangle (start 3.81 -109.093) (end 5.08 -109.347)
          (stroke (width 0.254) (type default))
          (fill (type background))
        )
        (rectangle (start 3.81 -106.553) (end 5.08 -106.807)
          (stroke (width 0.254) (type default))
          (fill (type background))
        )
        (rectangle (start 3.81 -104.013) (end 5.08 -104.267)
          (stroke (width 0.254) (type default))
          (fill (type background))
        )
        (rectangle (start 3.81 -101.473) (end 5.08 -101.727)
          (stroke (width 0.254) (type default))
          (fill (type background))
        )
        (rectangle (start 3.81 -98.933) (end 5.08 -99.187)
          (stroke (width 0.254) (type default))
          (fill (type background))
        )
        (rectangle (start 3.81 -96.393) (end 5.08 -96.647)
          (stroke (width 0.254) (type default))
          (fill (type background))
        )
        (rectangle (start 3.81 -93.853) (end 5.08 -94.107)
          (stroke (width 0.254) (type default))
          (fill (type background))
        )
        (rectangle (start 3.81 -91.313) (end 5.08 -91.567)
          (stroke (width 0.254) (type default))
          (fill (type background))
        )
        (rectangle (start 3.81 -88.773) (end 5.08 -89.027)
          (stroke (width 0.254) (type default))
          (fill (type background))
        )
        (rectangle (start 3.81 -86.233) (end 5.08 -86.487)
          (stroke (width 0.254) (type default))
          (fill (type background))
        )
        (rectangle (start 3.81 -83.693) (end 5.08 -83.947)
          (stroke (width 0.254) (type default))
          (fill (type background))
        )
        (rectangle (start 3.81 -81.153) (end 5.08 -81.407)
          (stroke (width 0.254) (type default))
          (fill (type background))
        )
        (rectangle (start 3.81 -78.613) (end 5.08 -78.867)
          (stroke (width 0.254) (type default))
          (fill (type background))
        )
        (rectangle (start 3.81 -76.073) (end 5.08 -76.327)
          (stroke (width 0.254) (type default))
          (fill (type background))
        )
        (rectangle (start 3.81 -73.533) (end 5.08 -73.787)
          (stroke (width 0.254) (type default))
          (fill (type background))
        )
        (rectangle (start 3.81 -70.993) (end 5.08 -71.247)
          (stroke (width 0.254) (type default))
          (fill (type background))
        )
        (rectangle (start 3.81 -68.453) (end 5.08 -68.707)
          (stroke (width 0.254) (type default))
          (fill (type background))
        )
        (rectangle (start 3.81 -65.913) (end 5.08 -66.167)
          (stroke (width 0.254) (type default))
          (fill (type background))
        )
        (rectangle (start 3.81 -63.373) (end 5.08 -63.627)
          (stroke (width 0.254) (type default))
          (fill (type background))
        )
        (rectangle (start 3.81 -60.833) (end 5.08 -61.087)
          (stroke (width 0.254) (type default))
          (fill (type background))
        )
        (rectangle (start 3.81 -58.293) (end 5.08 -58.547)
          (stroke (width 0.254) (type default))
          (fill (type background))
        )
        (rectangle (start 3.81 -55.753) (end 5.08 -56.007)
          (stroke (width 0.254) (type default))
          (fill (type background))
        )
        (rectangle (start 3.81 -53.213) (end 5.08 -53.467)
          (stroke (width 0.254) (type default))
          (fill (type background))
        )
        (rectangle (start 3.81 -50.673) (end 5.08 -50.927)
          (stroke (width 0.254) (type default))
          (fill (type background))
        )
        (rectangle (start 3.81 -48.133) (end 5.08 -48.387)
          (stroke (width 0.254) (type default))
          (fill (type background))
        )
        (rectangle (start 3.81 -45.593) (end 5.08 -45.847)
          (stroke (width 0.254) (type default))
          (fill (type background))
        )
        (rectangle (start 3.81 -43.053) (end 5.08 -43.307)
          (stroke (width 0.254) (type default))
          (fill (type background))
        )
        (rectangle (start 3.81 -40.513) (end 5.08 -40.767)
          (stroke (width 0.254) (type default))
          (fill (type background))
        )
        (rectangle (start 3.81 -37.973) (end 5.08 -38.227)
          (stroke (width 0.254) (type default))
          (fill (type background))
        )
        (rectangle (start 3.81 -35.433) (end 5.08 -35.687)
          (stroke (width 0.254) (type default))
          (fill (type background))
        )
        (rectangle (start 3.81 -32.893) (end 5.08 -33.147)
          (stroke (width 0.254) (type default))
          (fill (type background))
        )
        (rectangle (start 3.81 -30.353) (end 5.08 -30.607)
          (stroke (width 0.254) (type default))
          (fill (type background))
        )
        (rectangle (start 3.81 -27.813) (end 5.08 -28.067)
          (stroke (width 0.254) (type default))
          (fill (type background))
        )
        (rectangle (start 3.81 -25.273) (end 5.08 -25.527)
          (stroke (width 0.254) (type default))
          (fill (type background))
        )
        (rectangle (start 3.81 -22.733) (end 5.08 -22.987)
          (stroke (width 0.254) (type default))
          (fill (type background))
        )
        (rectangle (start 3.81 -20.193) (end 5.08 -20.447)
          (stroke (width 0.254) (type default))
          (fill (type background))
        )
        (rectangle (start 3.81 -17.653) (end 5.08 -17.907)
          (stroke (width 0.254) (type default))
          (fill (type background))
        )
        (rectangle (start 3.81 -15.113) (end 5.08 -15.367)
          (stroke (width 0.254) (type default))
          (fill (type background))
        )
        (rectangle (start 3.81 -12.573) (end 5.08 -12.827)
          (stroke (width 0.254) (type default))
          (fill (type background))
        )
        (rectangle (start 3.81 -10.033) (end 5.08 -10.287)
          (stroke (width 0.254) (type default))
          (fill (type background))
        )
        (rectangle (start 3.81 -7.493) (end 5.08 -7.747)
          (stroke (width 0.254) (type default))
          (fill (type background))
        )
        (rectangle (start 3.81 -4.953) (end 5.08 -5.207)
          (stroke (width 0.254) (type default))
          (fill (type background))
        )
        (rectangle (start 3.81 -2.413) (end 5.08 -2.667)
          (stroke (width 0.254) (type default))
          (fill (type background))
        )
        (rectangle (start 3.81 0.127) (end 5.08 -0.127)
          (stroke (width 0.254) (type default))
          (fill (type background))
        )
        (rectangle (start 3.81 1.27) (end 7.62 -132.08)
          (stroke (width 0.254) (type default))
          (fill (type background))
        )
        (pin passive line (at 0 0 0) (length 3.81)
          (name "~" (effects (font (size 1.27 1.27))))
          (number "1" (effects (font (size 1.27 1.27))))
        )
        (pin passive line (at 0 -22.86 0) (length 3.81)
          (name "~" (effects (font (size 1.27 1.27))))
          (number "10" (effects (font (size 1.27 1.27))))
        )
        (pin passive line (at 0 -25.4 0) (length 3.81)
          (name "~" (effects (font (size 1.27 1.27))))
          (number "11" (effects (font (size 1.27 1.27))))
        )
        (pin passive line (at 0 -27.94 0) (length 3.81)
          (name "~" (effects (font (size 1.27 1.27))))
          (number "12" (effects (font (size 1.27 1.27))))
        )
        (pin passive line (at 0 -30.48 0) (length 3.81)
          (name "~" (effects (font (size 1.27 1.27))))
          (number "13" (effects (font (size 1.27 1.27))))
        )
        (pin passive line (at 0 -33.02 0) (length 3.81)
          (name "~" (effects (font (size 1.27 1.27))))
          (number "14" (effects (font (size 1.27 1.27))))
        )
        (pin passive line (at 0 -35.56 0) (length 3.81)
          (name "~" (effects (font (size 1.27 1.27))))
          (number "15" (effects (font (size 1.27 1.27))))
        )
        (pin passive line (at 0 -38.1 0) (length 3.81)
          (name "~" (effects (font (size 1.27 1.27))))
          (number "16" (effects (font (size 1.27 1.27))))
        )
        (pin passive line (at 0 -40.64 0) (length 3.81)
          (name "~" (effects (font (size 1.27 1.27))))
          (number "17" (effects (font (size 1.27 1.27))))
        )
        (pin passive line (at 0 -43.18 0) (length 3.81)
          (name "~" (effects (font (size 1.27 1.27))))
          (number "18" (effects (font (size 1.27 1.27))))
        )
        (pin passive line (at 0 -45.72 0) (length 3.81)
          (name "~" (effects (font (size 1.27 1.27))))
          (number "19" (effects (font (size 1.27 1.27))))
        )
        (pin passive line (at 0 -2.54 0) (length 3.81)
          (name "~" (effects (font (size 1.27 1.27))))
          (number "2" (effects (font (size 1.27 1.27))))
        )
        (pin passive line (at 0 -48.26 0) (length 3.81)
          (name "~" (effects (font (size 1.27 1.27))))
          (number "20" (effects (font (size 1.27 1.27))))
        )
        (pin passive line (at 0 -50.8 0) (length 3.81)
          (name "~" (effects (font (size 1.27 1.27))))
          (number "21" (effects (font (size 1.27 1.27))))
        )
        (pin passive line (at 0 -53.34 0) (length 3.81)
          (name "~" (effects (font (size 1.27 1.27))))
          (number "22" (effects (font (size 1.27 1.27))))
        )
        (pin passive line (at 0 -55.88 0) (length 3.81)
          (name "~" (effects (font (size 1.27 1.27))))
          (number "23" (effects (font (size 1.27 1.27))))
        )
        (pin passive line (at 0 -58.42 0) (length 3.81)
          (name "~" (effects (font (size 1.27 1.27))))
          (number "24" (effects (font (size 1.27 1.27))))
        )
        (pin passive line (at 0 -60.96 0) (length 3.81)
          (name "~" (effects (font (size 1.27 1.27))))
          (number "25" (effects (font (size 1.27 1.27))))
        )
        (pin passive line (at 0 -63.5 0) (length 3.81)
          (name "~" (effects (font (size 1.27 1.27))))
          (number "26" (effects (font (size 1.27 1.27))))
        )
        (pin passive line (at 0 -66.04 0) (length 3.81)
          (name "~" (effects (font (size 1.27 1.27))))
          (number "27" (effects (font (size 1.27 1.27))))
        )
        (pin passive line (at 0 -68.58 0) (length 3.81)
          (name "~" (effects (font (size 1.27 1.27))))
          (number "28" (effects (font (size 1.27 1.27))))
        )
        (pin passive line (at 0 -71.12 0) (length 3.81)
          (name "~" (effects (font (size 1.27 1.27))))
          (number "29" (effects (font (size 1.27 1.27))))
        )
        (pin passive line (at 0 -5.08 0) (length 3.81)
          (name "~" (effects (font (size 1.27 1.27))))
          (number "3" (effects (font (size 1.27 1.27))))
        )
        (pin passive line (at 0 -73.66 0) (length 3.81)
          (name "~" (effects (font (size 1.27 1.27))))
          (number "30" (effects (font (size 1.27 1.27))))
        )
        (pin passive line (at 0 -76.2 0) (length 3.81)
          (name "~" (effects (font (size 1.27 1.27))))
          (number "31" (effects (font (size 1.27 1.27))))
        )
        (pin passive line (at 0 -78.74 0) (length 3.81)
          (name "~" (effects (font (size 1.27 1.27))))
          (number "32" (effects (font (size 1.27 1.27))))
        )
        (pin passive line (at 0 -81.28 0) (length 3.81)
          (name "~" (effects (font (size 1.27 1.27))))
          (number "33" (effects (font (size 1.27 1.27))))
        )
        (pin passive line (at 0 -83.82 0) (length 3.81)
          (name "~" (effects (font (size 1.27 1.27))))
          (number "34" (effects (font (size 1.27 1.27))))
        )
        (pin passive line (at 0 -86.36 0) (length 3.81)
          (name "~" (effects (font (size 1.27 1.27))))
          (number "35" (effects (font (size 1.27 1.27))))
        )
        (pin passive line (at 0 -88.9 0) (length 3.81)
          (name "~" (effects (font (size 1.27 1.27))))
          (number "36" (effects (font (size 1.27 1.27))))
        )
        (pin passive line (at 0 -91.44 0) (length 3.81)
          (name "~" (effects (font (size 1.27 1.27))))
          (number "37" (effects (font (size 1.27 1.27))))
        )
        (pin passive line (at 0 -93.98 0) (length 3.81)
          (name "~" (effects (font (size 1.27 1.27))))
          (number "38" (effects (font (size 1.27 1.27))))
        )
        (pin passive line (at 0 -96.52 0) (length 3.81)
          (name "~" (effects (font (size 1.27 1.27))))
          (number "39" (effects (font (size 1.27 1.27))))
        )
        (pin passive line (at 0 -7.62 0) (length 3.81)
          (name "~" (effects (font (size 1.27 1.27))))
          (number "4" (effects (font (size 1.27 1.27))))
        )
        (pin passive line (at 0 -99.06 0) (length 3.81)
          (name "~" (effects (font (size 1.27 1.27))))
          (number "40" (effects (font (size 1.27 1.27))))
        )
        (pin passive line (at 0 -101.6 0) (length 3.81)
          (name "~" (effects (font (size 1.27 1.27))))
          (number "41" (effects (font (size 1.27 1.27))))
        )
        (pin passive line (at 0 -104.14 0) (length 3.81)
          (name "~" (effects (font (size 1.27 1.27))))
          (number "42" (effects (font (size 1.27 1.27))))
        )
        (pin passive line (at 0 -106.68 0) (length 3.81)
          (name "~" (effects (font (size 1.27 1.27))))
          (number "43" (effects (font (size 1.27 1.27))))
        )
        (pin passive line (at 0 -109.22 0) (length 3.81)
          (name "~" (effects (font (size 1.27 1.27))))
          (number "44" (effects (font (size 1.27 1.27))))
        )
        (pin passive line (at 0 -111.76 0) (length 3.81)
          (name "~" (effects (font (size 1.27 1.27))))
          (number "45" (effects (font (size 1.27 1.27))))
        )
        (pin passive line (at 0 -114.3 0) (length 3.81)
          (name "~" (effects (font (size 1.27 1.27))))
          (number "46" (effects (font (size 1.27 1.27))))
        )
        (pin passive line (at 0 -116.84 0) (length 3.81)
          (name "~" (effects (font (size 1.27 1.27))))
          (number "47" (effects (font (size 1.27 1.27))))
        )
        (pin passive line (at 0 -119.38 0) (length 3.81)
          (name "~" (effects (font (size 1.27 1.27))))
          (number "48" (effects (font (size 1.27 1.27))))
        )
        (pin passive line (at 0 -121.92 0) (length 3.81)
          (name "~" (effects (font (size 1.27 1.27))))
          (number "49" (effects (font (size 1.27 1.27))))
        )
        (pin passive line (at 0 -10.16 0) (length 3.81)
          (name "~" (effects (font (size 1.27 1.27))))
          (number "5" (effects (font (size 1.27 1.27))))
        )
        (pin passive line (at 0 -124.46 0) (length 3.81)
          (name "~" (effects (font (size 1.27 1.27))))
          (number "50" (effects (font (size 1.27 1.27))))
        )
        (pin passive line (at 0 -12.7 0) (length 3.81)
          (name "~" (effects (font (size 1.27 1.27))))
          (number "6" (effects (font (size 1.27 1.27))))
        )
        (pin passive line (at 0 -15.24 0) (length 3.81)
          (name "~" (effects (font (size 1.27 1.27))))
          (number "7" (effects (font (size 1.27 1.27))))
        )
        (pin passive line (at 0 -17.78 0) (length 3.81)
          (name "~" (effects (font (size 1.27 1.27))))
          (number "8" (effects (font (size 1.27 1.27))))
        )
        (pin passive line (at 0 -20.32 0) (length 3.81)
          (name "~" (effects (font (size 1.27 1.27))))
          (number "9" (effects (font (size 1.27 1.27))))
        )
        (pin passive line (at 0 -127 0) (length 3.81)
          (name "MP" (effects (font (size 1.27 1.27))))
          (number "MP1" (effects (font (size 1.27 1.27))))
        )
        (pin passive line (at 0 -129.54 0) (length 3.81)
          (name "MP" (effects (font (size 1.27 1.27))))
          (number "MP2" (effects (font (size 1.27 1.27))))
        )
      )
    )
	(symbol "antmicroFerriteBeadsandChips:FB_120Z_3A_Murata-BLM18SG_0603" (pin_numbers hide) (pin_names hide) (in_bom yes) (on_board yes)
      (property "Reference" "FB" (at 13.97 0 0)
        (effects (font (size 1.27 1.27) (thickness 0.15)) (justify left bottom))
      )
      (property "Value" "FB_120Z_3A_Murata-BLM18SG_0603" (at 13.97 -2.54 0)
        (effects (font (size 1.27 1.27) (thickness 0.15)) (justify left bottom) hide)
      )
      (property "Footprint" "antmicro-footprints:FB_0603_1608Metric" (at 13.97 -7.62 0)
        (effects (font (size 1.27 1.27) (thickness 0.15)) (justify left bottom) hide)
      )
      (property "Datasheet" "https://www.murata.com/products/productdata/8796738650142/ENFA0003.pdf?1681308024000" (at 13.97 -10.16 0)
        (effects (font (size 1.27 1.27) (thickness 0.15)) (justify left bottom) hide)
      )
      (property "Val" "120Z/3A" (at 13.97 -5.08 0)
        (effects (font (size 1.27 1.27)) (justify left bottom))
      )
      (property "MPN" "BLM18SG121TN1D" (at 13.97 -12.7 0)
        (effects (font (size 1.27 1.27) (thickness 0.15)) (justify left bottom) hide)
      )
      (property "Manufacturer" "Murata" (at 13.97 -15.24 0)
        (effects (font (size 1.27 1.27) (thickness 0.15)) (justify left bottom) hide)
      )
      (property "Current" "" (at 20.32 -22.86 0)
        (effects (font (size 1.27 1.27) (thickness 0.15)) (justify left bottom) hide)
      )
      (property "Author" "Antmicro" (at 13.97 -17.78 0)
        (effects (font (size 1.27 1.27) (thickness 0.15)) (justify left bottom) hide)
      )
      (property "License" "Apache-2.0" (at 13.97 -20.32 0)
        (effects (font (size 1.27 1.27) (thickness 0.15)) (justify left bottom) hide)
      )
      (property "Public" "False" (at 20.32 -15.24 0)
        (effects (font (size 1.27 1.27)) (justify left bottom) hide)
      )
      (property "ki_keywords" "0603, SMT, FERRITE BEAD, PASSIVE" (at 0 0 0)
        (effects (font (size 1.27 1.27)) hide)
      )
      (property "ki_description" "Ferrite Bead, 0603 [1608 Metric], 120 ohm, 3 A, BLM18S, 0.025 ohm, ± 25%, DC power line (thin type) " (at 0 0 0)
        (effects (font (size 1.27 1.27)) hide)
      )
      (symbol "FB_120Z_3A_Murata-BLM18SG_0603_0_1"
        (polyline
          (pts
            (xy 1.651 0)
            (xy 1.2446 0)
          )
          (stroke (width 0) (type default))
          (fill (type none))
        )
        (polyline
          (pts
            (xy 3.81 0)
            (xy 3.3274 0)
          )
          (stroke (width 0) (type default))
          (fill (type none))
        )
        (polyline
          (pts
            (xy 2.2606 -1.8288)
            (xy 1.0414 -1.1176)
            (xy 2.7432 1.8288)
            (xy 3.9624 1.1176)
            (xy 2.2606 -1.8288)
          )
          (stroke (width 0) (type default))
          (fill (type none))
        )
      )
      (symbol "FB_120Z_3A_Murata-BLM18SG_0603_1_1"
        (pin passive line (at 0 0 0) (length 1.27)
          (name "~" (effects (font (size 1.27 1.27))))
          (number "1" (effects (font (size 1.27 1.27))))
        )
        (pin passive line (at 5.08 0 180) (length 1.27)
          (name "~" (effects (font (size 1.27 1.27))))
          (number "2" (effects (font (size 1.27 1.27))))
        )
      )
    )
	(symbol "antmicroFerriteBeadsandChips:FB_1kZ_0.8A_WE-CBF_0805" (pin_numbers hide) (pin_names hide) (in_bom yes) (on_board yes)
      (property "Reference" "FB" (at 15.24 0 0)
        (effects (font (size 1.27 1.27) (thickness 0.15)) (justify left bottom))
      )
      (property "Value" "FB_1kZ_0.8A_WE-CBF_0805" (at 15.24 -8.128 0)
        (effects (font (size 1.27 1.27) (thickness 0.15)) (justify left bottom) hide)
      )
      (property "Footprint" "antmicro-footprints:FB_0805_2012Metric" (at 15.24 -10.668 0)
        (effects (font (size 1.27 1.27) (thickness 0.15)) (justify left bottom) hide)
      )
      (property "Datasheet" "https://www.we-online.com/components/products/datasheet/742792096.pdf" (at 15.24 -13.208 0)
        (effects (font (size 1.27 1.27) (thickness 0.15)) (justify left bottom) hide)
      )
      (property "Val" "1kZ/0.8A" (at 15.24 -5.08 0)
        (effects (font (size 1.27 1.27)) (justify left bottom))
      )
      (property "MPN" "742792096" (at 15.24 -2.54 0)
        (effects (font (size 1.27 1.27) (thickness 0.15)) (justify left bottom) hide)
      )
      (property "Manufacturer" "Würth Elektronik" (at 15.24 -15.748 0)
        (effects (font (size 1.27 1.27) (thickness 0.15)) (justify left bottom) hide)
      )
      (property "Current" "" (at 20.32 -22.86 0)
        (effects (font (size 1.27 1.27) (thickness 0.15)) (justify left bottom) hide)
      )
      (property "Author" "Antmicro" (at 15.24 -18.288 0)
        (effects (font (size 1.27 1.27) (thickness 0.15)) (justify left bottom) hide)
      )
      (property "License" "Apache-2.0" (at 15.24 -20.828 0)
        (effects (font (size 1.27 1.27) (thickness 0.15)) (justify left bottom) hide)
      )
      (property "Public" "False" (at 20.32 -15.24 0)
        (effects (font (size 1.27 1.27)) (justify left bottom) hide)
      )
      (property "ki_keywords" "FERRITE BEAD, PASSIVE" (at 0 0 0)
        (effects (font (size 1.27 1.27)) hide)
      )
      (property "ki_description" "Ferrite Beads WE-CBF 0805 100MHz 1kOhm 1A, High Current" (at 0 0 0)
        (effects (font (size 1.27 1.27)) hide)
      )
      (symbol "FB_1kZ_0.8A_WE-CBF_0805_0_1"
        (polyline
          (pts
            (xy 1.651 0)
            (xy 1.2446 0)
          )
          (stroke (width 0) (type default))
          (fill (type none))
        )
        (polyline
          (pts
            (xy 3.81 0)
            (xy 3.3274 0)
          )
          (stroke (width 0) (type default))
          (fill (type none))
        )
        (polyline
          (pts
            (xy 2.2606 -1.8288)
            (xy 1.0414 -1.1176)
            (xy 2.7432 1.8288)
            (xy 3.9624 1.1176)
            (xy 2.2606 -1.8288)
          )
          (stroke (width 0) (type default))
          (fill (type none))
        )
      )
      (symbol "FB_1kZ_0.8A_WE-CBF_0805_1_1"
        (pin passive line (at 0 0 0) (length 1.27)
          (name "~" (effects (font (size 1.27 1.27))))
          (number "1" (effects (font (size 1.27 1.27))))
        )
        (pin passive line (at 5.08 0 180) (length 1.27)
          (name "~" (effects (font (size 1.27 1.27))))
          (number "2" (effects (font (size 1.27 1.27))))
        )
      )
    )
	(symbol "antmicroFerriteBeadsandChips:FB_600Z_0.5A_Murata-BLM18AG_0603" (pin_numbers hide) (pin_names hide) (in_bom yes) (on_board yes)
      (property "Reference" "FB" (at 15.24 0 0)
        (effects (font (size 1.27 1.27) (thickness 0.15)) (justify left bottom))
      )
      (property "Value" "FB_600Z_0.5A_Murata-BLM18AG_0603" (at 15.24 -2.54 0)
        (effects (font (size 1.27 1.27) (thickness 0.15)) (justify left bottom) hide)
      )
      (property "Footprint" "antmicro-footprints:FB_0603_1608Metric" (at 15.24 -7.62 0)
        (effects (font (size 1.27 1.27) (thickness 0.15)) (justify left bottom) hide)
      )
      (property "Datasheet" "https://www.murata.com/en-us/products/productdata/8796738650142/ENFA0003.pdf" (at 15.24 -10.16 0)
        (effects (font (size 1.27 1.27) (thickness 0.15)) (justify left bottom) hide)
      )
      (property "Val" "600Z/0.5A" (at 15.24 -5.08 0)
        (effects (font (size 1.27 1.27)) (justify left bottom))
      )
      (property "MPN" "BLM18AG601SN1D" (at 15.24 -12.7 0)
        (effects (font (size 1.27 1.27) (thickness 0.15)) (justify left bottom) hide)
      )
      (property "Manufacturer" "Murata" (at 15.24 -15.24 0)
        (effects (font (size 1.27 1.27) (thickness 0.15)) (justify left bottom) hide)
      )
      (property "Current" "" (at 20.32 -22.86 0)
        (effects (font (size 1.27 1.27) (thickness 0.15)) (justify left bottom) hide)
      )
      (property "Author" "Antmicro" (at 15.24 -17.78 0)
        (effects (font (size 1.27 1.27) (thickness 0.15)) (justify left bottom) hide)
      )
      (property "License" "Apache-2.0" (at 15.24 -20.32 0)
        (effects (font (size 1.27 1.27) (thickness 0.15)) (justify left bottom) hide)
      )
      (property "Public" "False" (at 20.32 -15.24 0)
        (effects (font (size 1.27 1.27)) (justify left bottom) hide)
      )
      (property "ki_keywords" "0603, SMT, FERRITE BEAD, PASSIVE" (at 0 0 0)
        (effects (font (size 1.27 1.27)) hide)
      )
      (property "ki_description" "Ferrite Bead, 0603 [1608 Metric], 600 ohm, 500 mA, BLM18A, 0.38 ohm, ± 25%, General use" (at 0 0 0)
        (effects (font (size 1.27 1.27)) hide)
      )
      (symbol "FB_600Z_0.5A_Murata-BLM18AG_0603_0_1"
        (polyline
          (pts
            (xy 1.651 0)
            (xy 1.2446 0)
          )
          (stroke (width 0) (type default))
          (fill (type none))
        )
        (polyline
          (pts
            (xy 3.81 0)
            (xy 3.3274 0)
          )
          (stroke (width 0) (type default))
          (fill (type none))
        )
        (polyline
          (pts
            (xy 2.2606 -1.8288)
            (xy 1.0414 -1.1176)
            (xy 2.7432 1.8288)
            (xy 3.9624 1.1176)
            (xy 2.2606 -1.8288)
          )
          (stroke (width 0) (type default))
          (fill (type none))
        )
      )
      (symbol "FB_600Z_0.5A_Murata-BLM18AG_0603_1_1"
        (pin passive line (at 0 0 0) (length 1.27)
          (name "~" (effects (font (size 1.27 1.27))))
          (number "1" (effects (font (size 1.27 1.27))))
        )
        (pin passive line (at 5.08 0 180) (length 1.27)
          (name "~" (effects (font (size 1.27 1.27))))
          (number "2" (effects (font (size 1.27 1.27))))
        )
      )
    )
	(symbol "antmicroInterfaceControllers:TC358743XBG" (in_bom yes) (on_board yes)
      (property "Reference" "U" (at 40.64 10.16 0)
        (effects (font (size 1.27 1.27) (thickness 0.15)) (justify left bottom))
      )
      (property "Value" "TC358743XBG" (at 40.64 7.62 0)
        (effects (font (size 1.27 1.27) (thickness 0.15)) (justify left bottom) hide)
      )
      (property "Footprint" "antmicro-footprints:BGA-64_8x8_6.0x6.0mm" (at 40.64 5.08 0)
        (effects (font (size 1.27 1.27) (thickness 0.15)) (justify left bottom) hide)
      )
      (property "Datasheet" "https://toshiba.semicon-storage.com/info/TC358743XBG_datasheet_en_20171026.pdf?did=35655&prodName=TC358743XBG" (at 40.64 2.54 0)
        (effects (font (size 1.27 1.27) (thickness 0.15)) (justify left bottom) hide)
      )
      (property "MPN" "TC358743XBG" (at 40.64 0 0)
        (effects (font (size 1.27 1.27) (thickness 0.15)) (justify left bottom))
      )
      (property "Manufacturer" "Toshiba" (at 40.64 -2.54 0)
        (effects (font (size 1.27 1.27) (thickness 0.15)) (justify left bottom) hide)
      )
      (property "Author" "Antmicro" (at 40.64 -5.08 0)
        (effects (font (size 1.27 1.27) (thickness 0.15)) (justify left bottom) hide)
      )
      (property "License" "Apache-2.0" (at 40.64 -7.62 0)
        (effects (font (size 1.27 1.27) (thickness 0.15)) (justify left bottom) hide)
      )
      (property "ki_locked" "" (at 0 0 0)
        (effects (font (size 1.27 1.27)))
      )
      (property "ki_keywords" "SMT, INTERFACE, IC, CONTROLLER" (at 0 0 0)
        (effects (font (size 1.27 1.27)) hide)
      )
      (property "ki_description" "HDMI to MIPI CSI-2 bridge. Supports HDMI 1.4. MIPI CSI-2 compliant. 80-Pin VFBGA" (at 0 0 0)
        (effects (font (size 1.27 1.27)) hide)
      )
      (symbol "TC358743XBG_1_1"
        (rectangle (start 2.54 2.54) (end 27.94 -48.26)
          (stroke (width 0.254) (type default))
          (fill (type background))
        )
        (pin output line (at 30.48 -22.86 180) (length 2.54)
          (name "CSID3_N" (effects (font (size 1.27 1.27))))
          (number "A7" (effects (font (size 1.27 1.27))))
        )
        (pin output line (at 30.48 -20.32 180) (length 2.54)
          (name "CSID3_P" (effects (font (size 1.27 1.27))))
          (number "A8" (effects (font (size 1.27 1.27))))
        )
        (pin input line (at 0 -33.02 0) (length 2.54)
          (name "IR" (effects (font (size 1.27 1.27))))
          (number "B4" (effects (font (size 1.27 1.27))))
        )
        (pin output line (at 30.48 -17.78 180) (length 2.54)
          (name "CSID2_N" (effects (font (size 1.27 1.27))))
          (number "B7" (effects (font (size 1.27 1.27))))
        )
        (pin output line (at 30.48 -15.24 180) (length 2.54)
          (name "CSID2_P" (effects (font (size 1.27 1.27))))
          (number "B8" (effects (font (size 1.27 1.27))))
        )
        (pin input line (at 0 0 0) (length 2.54)
          (name "HDMIC_P" (effects (font (size 1.27 1.27))))
          (number "C1" (effects (font (size 1.27 1.27))))
        )
        (pin input line (at 0 -2.54 0) (length 2.54)
          (name "HDMIC_N" (effects (font (size 1.27 1.27))))
          (number "C2" (effects (font (size 1.27 1.27))))
        )
        (pin output line (at 30.48 -2.54 180) (length 2.54)
          (name "CSIC_N" (effects (font (size 1.27 1.27))))
          (number "C7" (effects (font (size 1.27 1.27))))
        )
        (pin output line (at 30.48 0 180) (length 2.54)
          (name "CSIC_P" (effects (font (size 1.27 1.27))))
          (number "C8" (effects (font (size 1.27 1.27))))
        )
        (pin input line (at 0 -5.08 0) (length 2.54)
          (name "HDMID0_P" (effects (font (size 1.27 1.27))))
          (number "D1" (effects (font (size 1.27 1.27))))
        )
        (pin input line (at 0 -7.62 0) (length 2.54)
          (name "HDMID0_N" (effects (font (size 1.27 1.27))))
          (number "D2" (effects (font (size 1.27 1.27))))
        )
        (pin output line (at 30.48 -12.7 180) (length 2.54)
          (name "CSID1_N" (effects (font (size 1.27 1.27))))
          (number "D7" (effects (font (size 1.27 1.27))))
        )
        (pin output line (at 30.48 -10.16 180) (length 2.54)
          (name "CSID1_P" (effects (font (size 1.27 1.27))))
          (number "D8" (effects (font (size 1.27 1.27))))
        )
        (pin input line (at 0 -10.16 0) (length 2.54)
          (name "HDMID1_P" (effects (font (size 1.27 1.27))))
          (number "E1" (effects (font (size 1.27 1.27))))
        )
        (pin input line (at 0 -12.7 0) (length 2.54)
          (name "HDMID1_N" (effects (font (size 1.27 1.27))))
          (number "E2" (effects (font (size 1.27 1.27))))
        )
        (pin output line (at 30.48 -7.62 180) (length 2.54)
          (name "CSID0_N" (effects (font (size 1.27 1.27))))
          (number "E7" (effects (font (size 1.27 1.27))))
        )
        (pin output line (at 30.48 -5.08 180) (length 2.54)
          (name "CSID0_P" (effects (font (size 1.27 1.27))))
          (number "E8" (effects (font (size 1.27 1.27))))
        )
        (pin input line (at 0 -15.24 0) (length 2.54)
          (name "HDMID2_P" (effects (font (size 1.27 1.27))))
          (number "F1" (effects (font (size 1.27 1.27))))
        )
        (pin input line (at 0 -17.78 0) (length 2.54)
          (name "HDMID2_N" (effects (font (size 1.27 1.27))))
          (number "F2" (effects (font (size 1.27 1.27))))
        )
        (pin bidirectional line (at 0 -22.86 0) (length 2.54)
          (name "CEC" (effects (font (size 1.27 1.27))))
          (number "G1" (effects (font (size 1.27 1.27))))
        )
        (pin bidirectional line (at 0 -43.18 0) (length 2.54)
          (name "DDC_SDA" (effects (font (size 1.27 1.27))))
          (number "G3" (effects (font (size 1.27 1.27))))
        )
        (pin bidirectional line (at 30.48 -33.02 180) (length 2.54)
          (name "I2C_SDA" (effects (font (size 1.27 1.27))))
          (number "G4" (effects (font (size 1.27 1.27))))
        )
        (pin bidirectional line (at 30.48 -43.18 180) (length 2.54)
          (name "EDID_SDA" (effects (font (size 1.27 1.27))))
          (number "G6" (effects (font (size 1.27 1.27))))
        )
        (pin output line (at 30.48 -27.94 180) (length 2.54)
          (name "HPDO" (effects (font (size 1.27 1.27))))
          (number "H1" (effects (font (size 1.27 1.27))))
        )
        (pin input line (at 0 -27.94 0) (length 2.54)
          (name "HPDI" (effects (font (size 1.27 1.27))))
          (number "H2" (effects (font (size 1.27 1.27))))
        )
        (pin bidirectional line (at 0 -45.72 0) (length 2.54)
          (name "DDC_SCL" (effects (font (size 1.27 1.27))))
          (number "H3" (effects (font (size 1.27 1.27))))
        )
        (pin bidirectional line (at 30.48 -35.56 180) (length 2.54)
          (name "I2C_SCL" (effects (font (size 1.27 1.27))))
          (number "H4" (effects (font (size 1.27 1.27))))
        )
        (pin bidirectional line (at 30.48 -45.72 180) (length 2.54)
          (name "EDID_SCL" (effects (font (size 1.27 1.27))))
          (number "H6" (effects (font (size 1.27 1.27))))
        )
      )
      (symbol "TC358743XBG_2_1"
        (rectangle (start 2.54 2.54) (end 22.86 -48.26)
          (stroke (width 0.254) (type default))
          (fill (type background))
        )
        (pin input line (at 0 0 0) (length 2.54)
          (name "REXT" (effects (font (size 1.27 1.27))))
          (number "A1" (effects (font (size 1.27 1.27))))
        )
        (pin power_in line (at 0 -22.86 0) (length 2.54)
          (name "GND" (effects (font (size 1.27 1.27))))
          (number "A2" (effects (font (size 1.27 1.27))))
        )
        (pin input line (at 0 -15.24 0) (length 2.54)
          (name "VPGM" (effects (font (size 1.27 1.27))))
          (number "A3" (effects (font (size 1.27 1.27))))
        )
        (pin power_in line (at 25.4 -10.16 180) (length 2.54)
          (name "AVDD33" (effects (font (size 1.27 1.27))))
          (number "B1" (effects (font (size 1.27 1.27))))
        )
        (pin power_in line (at 25.4 -22.86 180) (length 2.54)
          (name "AVDD12" (effects (font (size 1.27 1.27))))
          (number "B2" (effects (font (size 1.27 1.27))))
        )
        (pin output line (at 0 -10.16 0) (length 2.54)
          (name "INT" (effects (font (size 1.27 1.27))))
          (number "B3" (effects (font (size 1.27 1.27))))
        )
        (pin power_in line (at 25.4 -15.24 180) (length 2.54)
          (name "AVDD25" (effects (font (size 1.27 1.27))))
          (number "B5" (effects (font (size 1.27 1.27))))
        )
        (pin power_in line (at 25.4 -43.18 180) (length 2.54)
          (name "VDDC2" (effects (font (size 1.27 1.27))))
          (number "C3" (effects (font (size 1.27 1.27))))
        )
        (pin passive line (at 0 -22.86 0) (length 2.54) hide
          (name "GND" (effects (font (size 1.27 1.27))))
          (number "C4" (effects (font (size 1.27 1.27))))
        )
        (pin passive line (at 0 -22.86 0) (length 2.54) hide
          (name "GND" (effects (font (size 1.27 1.27))))
          (number "C5" (effects (font (size 1.27 1.27))))
        )
        (pin power_in line (at 25.4 -30.48 180) (length 2.54)
          (name "VDD_MIPI" (effects (font (size 1.27 1.27))))
          (number "C6" (effects (font (size 1.27 1.27))))
        )
        (pin passive line (at 25.4 -22.86 180) (length 2.54) hide
          (name "AVDD12" (effects (font (size 1.27 1.27))))
          (number "D3" (effects (font (size 1.27 1.27))))
        )
        (pin passive line (at 0 -22.86 0) (length 2.54) hide
          (name "GND" (effects (font (size 1.27 1.27))))
          (number "D4" (effects (font (size 1.27 1.27))))
        )
        (pin passive line (at 0 -22.86 0) (length 2.54) hide
          (name "GND" (effects (font (size 1.27 1.27))))
          (number "D5" (effects (font (size 1.27 1.27))))
        )
        (pin passive line (at 0 -22.86 0) (length 2.54) hide
          (name "GND" (effects (font (size 1.27 1.27))))
          (number "D6" (effects (font (size 1.27 1.27))))
        )
        (pin passive line (at 0 -22.86 0) (length 2.54) hide
          (name "GND" (effects (font (size 1.27 1.27))))
          (number "E3" (effects (font (size 1.27 1.27))))
        )
        (pin passive line (at 0 -22.86 0) (length 2.54) hide
          (name "GND" (effects (font (size 1.27 1.27))))
          (number "E4" (effects (font (size 1.27 1.27))))
        )
        (pin input line (at 0 -17.78 0) (length 2.54)
          (name "TEST" (effects (font (size 1.27 1.27))))
          (number "E5" (effects (font (size 1.27 1.27))))
        )
        (pin passive line (at 0 -22.86 0) (length 2.54) hide
          (name "GND" (effects (font (size 1.27 1.27))))
          (number "E6" (effects (font (size 1.27 1.27))))
        )
        (pin passive line (at 25.4 -10.16 180) (length 2.54) hide
          (name "AVDD33" (effects (font (size 1.27 1.27))))
          (number "F3" (effects (font (size 1.27 1.27))))
        )
        (pin power_in line (at 25.4 0 180) (length 2.54)
          (name "VDDIO1" (effects (font (size 1.27 1.27))))
          (number "F4" (effects (font (size 1.27 1.27))))
        )
        (pin passive line (at 25.4 -43.18 180) (length 2.54) hide
          (name "VDDC2" (effects (font (size 1.27 1.27))))
          (number "F5" (effects (font (size 1.27 1.27))))
        )
        (pin passive line (at 25.4 -30.48 180) (length 2.54) hide
          (name "VDD_MIPI" (effects (font (size 1.27 1.27))))
          (number "F6" (effects (font (size 1.27 1.27))))
        )
        (pin power_in line (at 25.4 -40.64 180) (length 2.54)
          (name "VDDC1" (effects (font (size 1.27 1.27))))
          (number "G2" (effects (font (size 1.27 1.27))))
        )
        (pin input line (at 0 -5.08 0) (length 2.54)
          (name "~{RESET}" (effects (font (size 1.27 1.27))))
          (number "G5" (effects (font (size 1.27 1.27))))
        )
        (pin input line (at 0 -7.62 0) (length 2.54)
          (name "REFCLK" (effects (font (size 1.27 1.27))))
          (number "H5" (effects (font (size 1.27 1.27))))
        )
        (pin power_in line (at 25.4 -2.54 180) (length 2.54)
          (name "VDDIO2" (effects (font (size 1.27 1.27))))
          (number "H7" (effects (font (size 1.27 1.27))))
        )
        (pin passive line (at 0 -22.86 0) (length 2.54) hide
          (name "GND" (effects (font (size 1.27 1.27))))
          (number "H8" (effects (font (size 1.27 1.27))))
        )
      )
      (symbol "TC358743XBG_3_1"
        (rectangle (start 2.54 2.54) (end 17.78 -20.32)
          (stroke (width 0.254) (type default))
          (fill (type background))
        )
        (pin output line (at 0 -10.16 0) (length 2.54)
          (name "BIASDA" (effects (font (size 1.27 1.27))))
          (number "A4" (effects (font (size 1.27 1.27))))
        )
        (pin output line (at 0 -12.7 0) (length 2.54)
          (name "DAOUT" (effects (font (size 1.27 1.27))))
          (number "A5" (effects (font (size 1.27 1.27))))
        )
        (pin output line (at 0 -15.24 0) (length 2.54)
          (name "PFIL" (effects (font (size 1.27 1.27))))
          (number "A6" (effects (font (size 1.27 1.27))))
        )
        (pin input line (at 0 -17.78 0) (length 2.54)
          (name "PCKIN" (effects (font (size 1.27 1.27))))
          (number "B6" (effects (font (size 1.27 1.27))))
        )
        (pin output line (at 0 -7.62 0) (length 2.54)
          (name "A_SCK" (effects (font (size 1.27 1.27))))
          (number "F7" (effects (font (size 1.27 1.27))))
        )
        (pin output line (at 0 -5.08 0) (length 2.54)
          (name "A_SD" (effects (font (size 1.27 1.27))))
          (number "F8" (effects (font (size 1.27 1.27))))
        )
        (pin output line (at 0 0 0) (length 2.54)
          (name "A_WFS" (effects (font (size 1.27 1.27))))
          (number "G7" (effects (font (size 1.27 1.27))))
        )
        (pin output line (at 0 -2.54 0) (length 2.54)
          (name "A_OSCK" (effects (font (size 1.27 1.27))))
          (number "G8" (effects (font (size 1.27 1.27))))
        )
      )
    )
	(symbol "antmicroLogicTranslatorsLevelShifters:PCA9517ATP" (in_bom yes) (on_board yes)
      (property "Reference" "U" (at 33.02 -2.54 0)
        (effects (font (size 1.27 1.27) (thickness 0.15)) (justify left bottom))
      )
      (property "Value" "PCA9517ATP" (at 33.02 -5.08 0)
        (effects (font (size 1.27 1.27) (thickness 0.15)) (justify left bottom))
      )
      (property "Footprint" "antmicro-footprints:SOT1069-2" (at 33.02 -7.62 0)
        (effects (font (size 1.27 1.27) (thickness 0.15)) (justify left bottom) hide)
      )
      (property "Datasheet" "https://www.nxp.com/docs/en/data-sheet/PCA9517A.pdf" (at 33.02 -10.16 0)
        (effects (font (size 1.27 1.27) (thickness 0.15)) (justify left bottom) hide)
      )
      (property "MPN" "PCA9517ATP" (at 33.02 -12.7 0)
        (effects (font (size 1.27 1.27) (thickness 0.15)) (justify left bottom) hide)
      )
      (property "Manufacturer" "NXP" (at 33.02 -15.24 0)
        (effects (font (size 1.27 1.27) (thickness 0.15)) (justify left bottom) hide)
      )
      (property "Author" "Antmicro" (at 33.02 -17.78 0)
        (effects (font (size 1.27 1.27) (thickness 0.15)) (justify left bottom) hide)
      )
      (property "License" "Apache-2.0" (at 33.02 -20.32 0)
        (effects (font (size 1.27 1.27) (thickness 0.15)) (justify left bottom) hide)
      )
      (property "ki_keywords" "SMT, LEVEL-SHIFTER, IC, I2C" (at 0 0 0)
        (effects (font (size 1.27 1.27)) hide)
      )
      (property "ki_description" "Level Translating I2C-Bus Repeater, 2 Inputs, 0.9 V to 5.5 V Supply, 50 mA Out, HWSON-8" (at 0 0 0)
        (effects (font (size 1.27 1.27)) hide)
      )
      (symbol "PCA9517ATP_1_1"
        (rectangle (start 2.54 2.54) (end 15.24 -10.16)
          (stroke (width 0.254) (type default))
          (fill (type background))
        )
        (pin power_in line (at 0 0 0) (length 2.54)
          (name "Vref1" (effects (font (size 1.27 1.27))))
          (number "1" (effects (font (size 1.27 1.27))))
        )
        (pin input line (at 0 -2.54 0) (length 2.54)
          (name "SCL1" (effects (font (size 1.27 1.27))))
          (number "2" (effects (font (size 1.27 1.27))))
        )
        (pin bidirectional line (at 0 -5.08 0) (length 2.54)
          (name "SDA1" (effects (font (size 1.27 1.27))))
          (number "3" (effects (font (size 1.27 1.27))))
        )
        (pin power_in line (at 0 -7.62 0) (length 2.54)
          (name "GND" (effects (font (size 1.27 1.27))))
          (number "4" (effects (font (size 1.27 1.27))))
        )
        (pin input line (at 17.78 -7.62 180) (length 2.54)
          (name "EN" (effects (font (size 1.27 1.27))))
          (number "5" (effects (font (size 1.27 1.27))))
        )
        (pin bidirectional line (at 17.78 -5.08 180) (length 2.54)
          (name "SDA2" (effects (font (size 1.27 1.27))))
          (number "6" (effects (font (size 1.27 1.27))))
        )
        (pin input line (at 17.78 -2.54 180) (length 2.54)
          (name "SCL2" (effects (font (size 1.27 1.27))))
          (number "7" (effects (font (size 1.27 1.27))))
        )
        (pin power_in line (at 17.78 0 180) (length 2.54)
          (name "Vref2" (effects (font (size 1.27 1.27))))
          (number "8" (effects (font (size 1.27 1.27))))
        )
        (pin passive line (at 0 -7.62 0) (length 2.54) hide
          (name "GND" (effects (font (size 1.27 1.27))))
          (number "9" (effects (font (size 1.27 1.27))))
        )
      )
    )
	(symbol "antmicroMechanicalParts:Spacer_Drill3.7mm_H6mm_9774060151R" (in_bom yes) (on_board yes)
      (property "Reference" "H" (at 22.86 -2.54 0)
        (effects (font (size 1.27 1.27) (thickness 0.15)) (justify left bottom))
      )
      (property "Value" "Spacer_Drill3.7mm_H6mm_9774060151R" (at 22.86 -5.08 0)
        (effects (font (size 1.27 1.27) (thickness 0.15)) (justify left bottom) hide)
      )
      (property "Footprint" "antmicro-footprints:Spacer_Drill3.7mm_H6mm_9774060151R" (at 22.86 -7.62 0)
        (effects (font (size 1.27 1.27) (thickness 0.15)) (justify left bottom) hide)
      )
      (property "Datasheet" "https://www.we-online.com/components/products/datasheet/9774060151R.pdf" (at 22.86 -10.16 0)
        (effects (font (size 1.27 1.27) (thickness 0.15)) (justify left bottom) hide)
      )
      (property "Manufacturer" "Würth Elektronik" (at 22.86 -12.7 0)
        (effects (font (size 1.27 1.27) (thickness 0.15)) (justify left bottom) hide)
      )
      (property "MPN" "9774060151R" (at 22.86 -15.24 0)
        (effects (font (size 1.27 1.27) (thickness 0.15)) (justify left bottom))
      )
      (property "Author" "Antmicro" (at 22.86 -17.78 0)
        (effects (font (size 1.27 1.27) (thickness 0.15)) (justify left bottom) hide)
      )
      (property "Public" "False" (at 22.86 -12.7 0)
        (effects (font (size 1.27 1.27)) (justify left bottom) hide)
      )
      (property "License" "Apache-2.0" (at 22.86 -20.32 0)
        (effects (font (size 1.27 1.27) (thickness 0.15)) (justify left bottom) hide)
      )
      (property "ki_keywords" "MECHANICAL, SPACER" (at 0 0 0)
        (effects (font (size 1.27 1.27)) hide)
      )
      (property "ki_description" "Spacer, SMT, Non Stop, Steel, Swage Round, 5.1 mm x 6 mm, M2.5 Thread, WA-SMSI Series" (at 0 0 0)
        (effects (font (size 1.27 1.27)) hide)
      )
      (symbol "Spacer_Drill3.7mm_H6mm_9774060151R_1_1"
        (rectangle (start 2.54 -2.54) (end 7.62 2.54)
          (stroke (width 0.254) (type default))
          (fill (type background))
        )
        (rectangle (start 3.81 -1.27) (end 6.35 1.27)
          (stroke (width 0.254) (type default))
          (fill (type background))
        )
        (pin passive line (at 0 0 0) (length 2.54)
          (name "~" (effects (font (size 1.27 1.27))))
          (number "1" (effects (font (size 1.27 1.27))))
        )
      )
    )
	(symbol "antmicroMechanicalParts:antmicro_logo" (in_bom no) (on_board yes)
      (property "Reference" "N" (at 15.24 -5.08 0)
        (effects (font (size 1.27 1.27) (thickness 0.15)) (justify left bottom))
      )
      (property "Value" "antmicro_logo" (at 15.24 -7.62 0)
        (effects (font (size 1.27 1.27) (thickness 0.15)) (justify left bottom))
      )
      (property "Footprint" "antmicro-footprints:antmicro-logo" (at 15.24 -10.16 0)
        (effects (font (size 1.27 1.27) (thickness 0.15)) (justify left bottom) hide)
      )
      (property "Datasheet" "" (at 15.24 -12.7 0)
        (effects (font (size 1.27 1.27) (thickness 0.15)) (justify left bottom) hide)
      )
      (property "MPN" "" (at 0 0 0)
        (effects (font (size 1.27 1.27)))
      )
      (property "Manufacturer" "" (at 15.24 -20.32 0)
        (effects (font (size 1.27 1.27) (thickness 0.15)) (justify left bottom) hide)
      )
      (property "Author" "Antmicro" (at 15.24 -15.24 0)
        (effects (font (size 1.27 1.27) (thickness 0.15)) (justify left bottom) hide)
      )
      (property "License" "Apache-2.0" (at 15.24 -17.78 0)
        (effects (font (size 1.27 1.27) (thickness 0.15)) (justify left bottom) hide)
      )
      (property "Public" "False" (at 15.24 -20.32 0)
        (effects (font (size 1.27 1.27)) (justify left bottom) hide)
      )
      (property "ki_description" "Mechanical part" (at 0 0 0)
        (effects (font (size 1.27 1.27)) hide)
      )
      (symbol "antmicro_logo_1_1"
        (text "Logo" (at 0 0 0)
          (effects (font (size 1.27 1.27) (thickness 0.15)) (justify left bottom))
        )
      )
    )
	(symbol "antmicroMechanicalParts:oshw_logo" (in_bom no) (on_board yes)
      (property "Reference" "N" (at 15.24 -5.08 0)
        (effects (font (size 1.27 1.27) (thickness 0.15)) (justify left bottom))
      )
      (property "Value" "oshw_logo" (at 15.24 -7.62 0)
        (effects (font (size 1.27 1.27) (thickness 0.15)) (justify left bottom))
      )
      (property "Footprint" "antmicro-footprints:oshw-logo" (at 15.24 -10.16 0)
        (effects (font (size 1.27 1.27) (thickness 0.15)) (justify left bottom) hide)
      )
      (property "Datasheet" "" (at 15.24 -12.7 0)
        (effects (font (size 1.27 1.27) (thickness 0.15)) (justify left bottom) hide)
      )
      (property "Author" "Antmicro" (at 15.24 -15.24 0)
        (effects (font (size 1.27 1.27) (thickness 0.15)) (justify left bottom) hide)
      )
      (property "License" "Apache-2.0" (at 15.24 -17.78 0)
        (effects (font (size 1.27 1.27) (thickness 0.15)) (justify left bottom) hide)
      )
      (property "MPN" "" (at 0 0 0)
        (effects (font (size 1.27 1.27)))
      )
      (property "Manufacturer" "" (at 15.24 -20.32 0)
        (effects (font (size 1.27 1.27) (thickness 0.15)) (justify left bottom) hide)
      )
      (property "Public" "False" (at 15.24 -20.32 0)
        (effects (font (size 1.27 1.27)) (justify left bottom) hide)
      )
      (property "ki_description" "Mechanical part" (at 0 0 0)
        (effects (font (size 1.27 1.27)) hide)
      )
      (symbol "oshw_logo_1_1"
        (text "Logo" (at 0 0 0)
          (effects (font (size 1.27 1.27) (thickness 0.15)) (justify left bottom))
        )
      )
    )
	(symbol "antmicroOscillators:Oscillator_27MHz_TXC_7C" (in_bom yes) (on_board yes)
      (property "Reference" "Y" (at 25.4 -1.905 0)
        (effects (font (size 1.27 1.27) (thickness 0.15)) (justify left bottom))
      )
      (property "Value" "Oscillator_27MHz_TXC_7C" (at 25.4 -12.065 0)
        (effects (font (size 1.27 1.27) (thickness 0.15)) (justify left bottom) hide)
      )
      (property "Footprint" "antmicro-footprints:Oscillator_SMD_TXC_7C_5x3.2x1.2mm" (at 25.4 -14.605 0)
        (effects (font (size 1.27 1.27) (thickness 0.15)) (justify left bottom) hide)
      )
      (property "Datasheet" "http://www.txccorp.com/download/products/oscillators/2015TXC_7C_57.pdf" (at 25.4 -17.145 0)
        (effects (font (size 1.27 1.27) (thickness 0.15)) (justify left bottom) hide)
      )
      (property "MPN" "7C-27.000MBB-T" (at 25.4 -4.445 0)
        (effects (font (size 1.27 1.27) (thickness 0.15)) (justify left bottom))
      )
      (property "Manufacturer" "TXC" (at 25.4 -6.985 0)
        (effects (font (size 1.27 1.27) (thickness 0.15)) (justify left bottom) hide)
      )
      (property "Val" "27 MHz" (at 25.4 -9.525 0)
        (effects (font (size 1.27 1.27) (thickness 0.15)) (justify left bottom))
      )
      (property "Author" "Antmicro" (at 25.4 -19.685 0)
        (effects (font (size 1.27 1.27) (thickness 0.15)) (justify left bottom) hide)
      )
      (property "License" "Apache-2.0" (at 25.4 -22.225 0)
        (effects (font (size 1.27 1.27) (thickness 0.15)) (justify left bottom) hide)
      )
      (property "Public" "False" (at 31.75 -24.13 0)
        (effects (font (size 1.27 1.27)) (justify left bottom) hide)
      )
      (property "ki_keywords" "OSCILLATOR" (at 0 0 0)
        (effects (font (size 1.27 1.27)) hide)
      )
      (property "ki_description" "Oscillator, 27 MHz, 50 ppm, SMT, 5mm x 3.2mm, 3.3 V, 7C Series" (at 0 0 0)
        (effects (font (size 1.27 1.27)) hide)
      )
      (symbol "Oscillator_27MHz_TXC_7C_1_1"
        (polyline
          (pts
            (xy 7.62 -1.27)
            (xy 8.255 -1.27)
            (xy 8.255 0)
            (xy 8.89 0)
            (xy 8.89 -1.27)
            (xy 9.525 -1.27)
            (xy 9.525 0)
            (xy 10.16 0)
            (xy 10.16 -1.27)
          )
          (stroke (width 0.254) (type default))
          (fill (type background))
        )
        (rectangle (start 2.54 2.54) (end 16.51 -7.62)
          (stroke (width 0.254) (type default))
          (fill (type background))
        )
        (pin input line (at 0 -2.54 0) (length 2.54)
          (name "EN" (effects (font (size 1.27 1.27))))
          (number "1" (effects (font (size 1.27 1.27))))
        )
        (pin power_in line (at 0 -5.08 0) (length 2.54)
          (name "GND" (effects (font (size 1.27 1.27))))
          (number "2" (effects (font (size 1.27 1.27))))
        )
        (pin output line (at 19.05 0 180) (length 2.54)
          (name "OUT" (effects (font (size 1.27 1.27))))
          (number "3" (effects (font (size 1.27 1.27))))
        )
        (pin power_in line (at 0 0 0) (length 2.54)
          (name "VDD" (effects (font (size 1.27 1.27))))
          (number "4" (effects (font (size 1.27 1.27))))
        )
      )
    )
	(symbol "antmicroPMICVoltageRegulatorsLinear:TLV73312PDBVT" (in_bom yes) (on_board yes)
      (property "Reference" "U" (at 35.56 -2.54 0)
        (effects (font (size 1.27 1.27) (thickness 0.15)) (justify left bottom))
      )
      (property "Value" "TLV73312PDBVT" (at 35.56 -5.08 0)
        (effects (font (size 1.27 1.27) (thickness 0.15)) (justify left bottom) hide)
      )
      (property "Footprint" "antmicro-footprints:SOT-23-5" (at 35.56 -7.62 0)
        (effects (font (size 1.27 1.27) (thickness 0.15)) (justify left bottom) hide)
      )
      (property "Datasheet" "https://www.ti.com/lit/ds/symlink/tlv733p.pdf?HQS=dis-mous-null-mousermode-dsf-pf-null-wwe&ts=1676978230940&ref_url=https%253A%252F%252Fwww.mouser.com%252F" (at 35.56 -10.16 0)
        (effects (font (size 1.27 1.27) (thickness 0.15)) (justify left bottom) hide)
      )
      (property "MPN" "TLV73312PDBVT" (at 35.56 -12.7 0)
        (effects (font (size 1.27 1.27) (thickness 0.15)) (justify left bottom))
      )
      (property "Manufacturer" "Texas Instruments" (at 35.56 -15.24 0)
        (effects (font (size 1.27 1.27) (thickness 0.15)) (justify left bottom) hide)
      )
      (property "Author" "Antmicro" (at 35.56 -17.78 0)
        (effects (font (size 1.27 1.27) (thickness 0.15)) (justify left bottom) hide)
      )
      (property "License" "Apache-2.0" (at 35.56 -20.32 0)
        (effects (font (size 1.27 1.27) (thickness 0.15)) (justify left bottom) hide)
      )
      (property "ki_keywords" "SMT, PMIC, IC, LDO, LINEAR, VOLTAGE, REGULATOR" (at 0 0 0)
        (effects (font (size 1.27 1.27)) hide)
      )
      (property "ki_description" "Fixed LDO Voltage Regulator, 1.4V to 5.5V, 122mV Dropout, 1.2Vout, 300mAout, SOT-23-5" (at 0 0 0)
        (effects (font (size 1.27 1.27)) hide)
      )
      (symbol "TLV73312PDBVT_1_1"
        (rectangle (start 2.54 2.54) (end 17.78 -5.08)
          (stroke (width 0.254) (type default))
          (fill (type background))
        )
        (pin power_in line (at 0 0 0) (length 2.54)
          (name "VIN" (effects (font (size 1.27 1.27))))
          (number "1" (effects (font (size 1.27 1.27))))
        )
        (pin power_in line (at 20.32 -2.54 180) (length 2.54)
          (name "GND" (effects (font (size 1.27 1.27))))
          (number "2" (effects (font (size 1.27 1.27))))
        )
        (pin input line (at 0 -2.54 0) (length 2.54)
          (name "EN" (effects (font (size 1.27 1.27))))
          (number "3" (effects (font (size 1.27 1.27))))
        )
        (pin no_connect line (at 20.32 -3.81 180) (length 2.54) hide
          (name "NC" (effects (font (size 1.27 1.27))))
          (number "4" (effects (font (size 1.27 1.27))))
        )
        (pin power_out line (at 20.32 0 180) (length 2.54)
          (name "VOUT" (effects (font (size 1.27 1.27))))
          (number "5" (effects (font (size 1.27 1.27))))
        )
      )
    )
	(symbol "antmicroPMICVoltageRegulatorsLinear:TLV73325PDBVT" (in_bom yes) (on_board yes)
      (property "Reference" "U" (at 35.56 -2.54 0)
        (effects (font (size 1.27 1.27) (thickness 0.15)) (justify left bottom))
      )
      (property "Value" "TLV73325PDBVT" (at 35.56 -5.08 0)
        (effects (font (size 1.27 1.27) (thickness 0.15)) (justify left bottom) hide)
      )
      (property "Footprint" "antmicro-footprints:SOT-23-5" (at 35.56 -7.62 0)
        (effects (font (size 1.27 1.27) (thickness 0.15)) (justify left bottom) hide)
      )
      (property "Datasheet" "https://www.ti.com/lit/ds/symlink/tlv733p.pdf?HQS=dis-mous-null-mousermode-dsf-pf-null-wwe&ts=1676978230940&ref_url=https%253A%252F%252Fwww.mouser.com%252F" (at 35.56 -10.16 0)
        (effects (font (size 1.27 1.27) (thickness 0.15)) (justify left bottom) hide)
      )
      (property "MPN" "TLV73325PDBVT" (at 35.56 -12.7 0)
        (effects (font (size 1.27 1.27) (thickness 0.15)) (justify left bottom))
      )
      (property "Manufacturer" "Texas Instruments" (at 35.56 -15.24 0)
        (effects (font (size 1.27 1.27) (thickness 0.15)) (justify left bottom) hide)
      )
      (property "Author" "Antmicro" (at 35.56 -17.78 0)
        (effects (font (size 1.27 1.27) (thickness 0.15)) (justify left bottom) hide)
      )
      (property "License" "Apache-2.0" (at 35.56 -20.32 0)
        (effects (font (size 1.27 1.27) (thickness 0.15)) (justify left bottom) hide)
      )
      (property "ki_keywords" "SMT, PMIC, IC, LDO, LINEAR, VOLTAGE, REGULATOR" (at 0 0 0)
        (effects (font (size 1.27 1.27)) hide)
      )
      (property "ki_description" "Linear voltage regulator" (at 0 0 0)
        (effects (font (size 1.27 1.27)) hide)
      )
      (symbol "TLV73325PDBVT_1_1"
        (rectangle (start 2.54 2.54) (end 17.78 -5.08)
          (stroke (width 0.254) (type default))
          (fill (type background))
        )
        (pin power_in line (at 0 0 0) (length 2.54)
          (name "VIN" (effects (font (size 1.27 1.27))))
          (number "1" (effects (font (size 1.27 1.27))))
        )
        (pin power_in line (at 20.32 -2.54 180) (length 2.54)
          (name "GND" (effects (font (size 1.27 1.27))))
          (number "2" (effects (font (size 1.27 1.27))))
        )
        (pin input line (at 0 -2.54 0) (length 2.54)
          (name "EN" (effects (font (size 1.27 1.27))))
          (number "3" (effects (font (size 1.27 1.27))))
        )
        (pin no_connect line (at 17.78 -3.81 0) (length 2.54) hide
          (name "NC" (effects (font (size 1.27 1.27))))
          (number "4" (effects (font (size 1.27 1.27))))
        )
        (pin power_out line (at 20.32 0 180) (length 2.54)
          (name "VOUT" (effects (font (size 1.27 1.27))))
          (number "5" (effects (font (size 1.27 1.27))))
        )
      )
    )
	(symbol "antmicroResistors0402:R_10k_0402" (pin_numbers hide) (pin_names hide) (in_bom yes) (on_board yes)
      (property "Reference" "R" (at 20.32 -5.08 0)
        (effects (font (size 1.27 1.27) (thickness 0.15)) (justify left bottom))
      )
      (property "Value" "R_10k_0402" (at 20.32 -12.7 0)
        (effects (font (size 1.27 1.27) (thickness 0.15)) (justify left bottom) hide)
      )
      (property "Footprint" "antmicro-footprints:R_0402_1005Metric" (at 20.32 -15.24 0)
        (effects (font (size 1.27 1.27) (thickness 0.15)) (justify left bottom) hide)
      )
      (property "Datasheet" "https://www.bourns.com/docs/product-datasheets/cr.pdf" (at 20.32 -17.78 0)
        (effects (font (size 1.27 1.27) (thickness 0.15)) (justify left bottom) hide)
      )
      (property "MPN" "CR0402-FX-1002GLF" (at 20.32 -20.32 0)
        (effects (font (size 1.27 1.27) (thickness 0.15)) (justify left bottom) hide)
      )
      (property "Manufacturer" "Bourns" (at 20.32 -22.86 0)
        (effects (font (size 1.27 1.27) (thickness 0.15)) (justify left bottom) hide)
      )
      (property "License" "Apache-2.0" (at 20.32 -25.4 0)
        (effects (font (size 1.27 1.27) (thickness 0.15)) (justify left bottom) hide)
      )
      (property "Author" "Antmicro" (at 20.32 -27.94 0)
        (effects (font (size 1.27 1.27) (thickness 0.15)) (justify left bottom) hide)
      )
      (property "Val" "10k" (at 20.32 -7.62 0)
        (effects (font (size 1.27 1.27) (thickness 0.15)) (justify left bottom))
      )
      (property "Tolerance" "1%" (at 20.32 -10.16 0)
        (effects (font (size 1.27 1.27)) (justify left bottom) hide)
      )
      (property "Public" "False" (at 20.32 -30.48 0)
        (effects (font (size 1.27 1.27)) (justify left bottom) hide)
      )
      (property "ki_keywords" "0402, SMT, RESISTOR, PASSIVE" (at 0 0 0)
        (effects (font (size 1.27 1.27)) hide)
      )
      (property "ki_description" "SMD Chip Resistor, 10 kohm, ± 1%, 62.5 mW, 0402 [1005 Metric], Thick Film, General Purpose" (at 0 0 0)
        (effects (font (size 1.27 1.27)) hide)
      )
      (symbol "R_10k_0402_0_1"
        (rectangle (start 0.635 0.889) (end 4.445 -0.889)
          (stroke (width 0.254) (type default))
          (fill (type none))
        )
      )
      (symbol "R_10k_0402_1_1"
        (pin passive line (at 0 0 0) (length 0.635)
          (name "~" (effects (font (size 1.27 1.27))))
          (number "1" (effects (font (size 1.27 1.27))))
        )
        (pin passive line (at 5.08 0 180) (length 0.635)
          (name "~" (effects (font (size 1.27 1.27))))
          (number "2" (effects (font (size 1.27 1.27))))
        )
      )
    )
	(symbol "antmicroResistors0402:R_22R_0402" (pin_numbers hide) (pin_names hide) (in_bom yes) (on_board yes)
      (property "Reference" "R" (at 20.32 -5.08 0)
        (effects (font (size 1.27 1.27) (thickness 0.15)) (justify left bottom))
      )
      (property "Value" "R_22R_0402" (at 20.32 -12.7 0)
        (effects (font (size 1.27 1.27) (thickness 0.15)) (justify left bottom) hide)
      )
      (property "Footprint" "antmicro-footprints:R_0402_1005Metric" (at 20.32 -15.24 0)
        (effects (font (size 1.27 1.27) (thickness 0.15)) (justify left bottom) hide)
      )
      (property "Datasheet" "https://www.bourns.com/docs/product-datasheets/cr.pdf" (at 20.32 -17.78 0)
        (effects (font (size 1.27 1.27) (thickness 0.15)) (justify left bottom) hide)
      )
      (property "MPN" "CR0402-FX-22R0GLF" (at 20.32 -20.32 0)
        (effects (font (size 1.27 1.27) (thickness 0.15)) (justify left bottom) hide)
      )
      (property "Manufacturer" "Bourns" (at 20.32 -22.86 0)
        (effects (font (size 1.27 1.27) (thickness 0.15)) (justify left bottom) hide)
      )
      (property "License" "Apache-2.0" (at 20.32 -25.4 0)
        (effects (font (size 1.27 1.27) (thickness 0.15)) (justify left bottom) hide)
      )
      (property "Author" "Antmicro" (at 20.32 -27.94 0)
        (effects (font (size 1.27 1.27) (thickness 0.15)) (justify left bottom) hide)
      )
      (property "Val" "22R" (at 20.32 -7.62 0)
        (effects (font (size 1.27 1.27) (thickness 0.15)) (justify left bottom))
      )
      (property "Tolerance" "1%" (at 20.32 -10.16 0)
        (effects (font (size 1.27 1.27)) (justify left bottom) hide)
      )
      (property "Public" "False" (at 20.32 -30.48 0)
        (effects (font (size 1.27 1.27)) (justify left bottom) hide)
      )
      (property "ki_keywords" "0402, SMT, RESISTOR, PASSIVE" (at 0 0 0)
        (effects (font (size 1.27 1.27)) hide)
      )
      (property "ki_description" "SMD Chip Resistor, 22 ohm, ± 1%, 62.5 mW, 0402 [1005 Metric], Thick Film, General Purpose" (at 0 0 0)
        (effects (font (size 1.27 1.27)) hide)
      )
      (symbol "R_22R_0402_0_1"
        (rectangle (start 0.635 0.889) (end 4.445 -0.889)
          (stroke (width 0.254) (type default))
          (fill (type none))
        )
      )
      (symbol "R_22R_0402_1_1"
        (pin passive line (at 0 0 0) (length 0.635)
          (name "~" (effects (font (size 1.27 1.27))))
          (number "1" (effects (font (size 1.27 1.27))))
        )
        (pin passive line (at 5.08 0 180) (length 0.635)
          (name "~" (effects (font (size 1.27 1.27))))
          (number "2" (effects (font (size 1.27 1.27))))
        )
      )
    )
	(symbol "antmicroResistors0402:R_2k_0402" (pin_numbers hide) (pin_names hide) (in_bom yes) (on_board yes)
      (property "Reference" "R" (at 20.32 -5.08 0)
        (effects (font (size 1.27 1.27) (thickness 0.15)) (justify left bottom))
      )
      (property "Value" "R_2k_0402" (at 20.32 -12.7 0)
        (effects (font (size 1.27 1.27) (thickness 0.15)) (justify left bottom) hide)
      )
      (property "Footprint" "antmicro-footprints:R_0402_1005Metric" (at 20.32 -15.24 0)
        (effects (font (size 1.27 1.27) (thickness 0.15)) (justify left bottom) hide)
      )
      (property "Datasheet" "https://www.bourns.com/docs/product-datasheets/cr.pdf" (at 20.32 -17.78 0)
        (effects (font (size 1.27 1.27) (thickness 0.15)) (justify left bottom) hide)
      )
      (property "MPN" "CR0402-FX-2001GLF" (at 20.32 -20.32 0)
        (effects (font (size 1.27 1.27) (thickness 0.15)) (justify left bottom) hide)
      )
      (property "Manufacturer" "Bourns" (at 20.32 -22.86 0)
        (effects (font (size 1.27 1.27) (thickness 0.15)) (justify left bottom) hide)
      )
      (property "License" "Apache-2.0" (at 20.32 -25.4 0)
        (effects (font (size 1.27 1.27) (thickness 0.15)) (justify left bottom) hide)
      )
      (property "Author" "Antmicro" (at 20.32 -27.94 0)
        (effects (font (size 1.27 1.27) (thickness 0.15)) (justify left bottom) hide)
      )
      (property "Val" "2k" (at 20.32 -7.62 0)
        (effects (font (size 1.27 1.27) (thickness 0.15)) (justify left bottom))
      )
      (property "Tolerance" "1%" (at 20.32 -10.16 0)
        (effects (font (size 1.27 1.27)) (justify left bottom) hide)
      )
      (property "Public" "False" (at 20.32 -30.48 0)
        (effects (font (size 1.27 1.27)) (justify left bottom) hide)
      )
      (property "ki_keywords" "0402, SMT, RESISTOR, PASSIVE" (at 0 0 0)
        (effects (font (size 1.27 1.27)) hide)
      )
      (property "ki_description" "SMD Chip Resistor, 2 kohm, ± 1%, 62.5 mW, 0402 [1005 Metric], Thick Film, General Purpose" (at 0 0 0)
        (effects (font (size 1.27 1.27)) hide)
      )
      (symbol "R_2k_0402_0_1"
        (rectangle (start 0.635 0.889) (end 4.445 -0.889)
          (stroke (width 0.254) (type default))
          (fill (type none))
        )
      )
      (symbol "R_2k_0402_1_1"
        (pin passive line (at 0 0 0) (length 0.635)
          (name "~" (effects (font (size 1.27 1.27))))
          (number "1" (effects (font (size 1.27 1.27))))
        )
        (pin passive line (at 5.08 0 180) (length 0.635)
          (name "~" (effects (font (size 1.27 1.27))))
          (number "2" (effects (font (size 1.27 1.27))))
        )
      )
    )
	(symbol "antmicroResistors0603:R_0R_0603" (pin_numbers hide) (pin_names hide) (in_bom yes) (on_board yes)
      (property "Reference" "R" (at 20.32 -5.08 0)
        (effects (font (size 1.27 1.27) (thickness 0.15)) (justify left bottom))
      )
      (property "Value" "R_0R_0603" (at 20.32 -12.7 0)
        (effects (font (size 1.27 1.27) (thickness 0.15)) (justify left bottom) hide)
      )
      (property "Footprint" "antmicro-footprints:R_0603_1608Metric" (at 20.32 -15.24 0)
        (effects (font (size 1.27 1.27) (thickness 0.15)) (justify left bottom) hide)
      )
      (property "Datasheet" "https://www.bourns.com/docs/product-datasheets/cr.pdf?sfvrsn=574d41f6_14" (at 20.32 -17.78 0)
        (effects (font (size 1.27 1.27) (thickness 0.15)) (justify left bottom) hide)
      )
      (property "MPN" "CR0603-J/-000ELF" (at 20.32 -20.32 0)
        (effects (font (size 1.27 1.27) (thickness 0.15)) (justify left bottom) hide)
      )
      (property "Manufacturer" "Bourns" (at 20.32 -22.86 0)
        (effects (font (size 1.27 1.27) (thickness 0.15)) (justify left bottom) hide)
      )
      (property "License" "Apache-2.0" (at 20.32 -25.4 0)
        (effects (font (size 1.27 1.27) (thickness 0.15)) (justify left bottom) hide)
      )
      (property "Author" "Antmicro" (at 20.32 -27.94 0)
        (effects (font (size 1.27 1.27) (thickness 0.15)) (justify left bottom) hide)
      )
      (property "Val" "0R" (at 20.32 -7.62 0)
        (effects (font (size 1.27 1.27) (thickness 0.15)) (justify left bottom))
      )
      (property "Tolerance" "~" (at 20.32 -10.16 0)
        (effects (font (size 1.27 1.27)) (justify left bottom) hide)
      )
      (property "Current" "1A" (at 20.32 -30.48 0)
        (effects (font (size 1.27 1.27) (thickness 0.15)) (justify left bottom) hide)
      )
      (property "Public" "False" (at 20.32 -30.48 0)
        (effects (font (size 1.27 1.27)) (justify left bottom) hide)
      )
      (property "ki_keywords" "0603, SMT, RESISTOR, PASSIVE" (at 0 0 0)
        (effects (font (size 1.27 1.27)) hide)
      )
      (property "ki_description" "Zero Ohm Resistor, Jumper, 0603 [1608 Metric], Thick Film, 100 mW, 1 A, Surface Mount Device, CR" (at 0 0 0)
        (effects (font (size 1.27 1.27)) hide)
      )
      (symbol "R_0R_0603_0_1"
        (rectangle (start 0.635 0.889) (end 4.445 -0.889)
          (stroke (width 0.254) (type default))
          (fill (type none))
        )
      )
      (symbol "R_0R_0603_1_1"
        (pin passive line (at 0 0 0) (length 0.635)
          (name "~" (effects (font (size 1.27 1.27))))
          (number "1" (effects (font (size 1.27 1.27))))
        )
        (pin passive line (at 5.08 0 180) (length 0.635)
          (name "~" (effects (font (size 1.27 1.27))))
          (number "2" (effects (font (size 1.27 1.27))))
        )
      )
    )
	(symbol "antmicroTVSDiodes:TPD8S009DSMR" (in_bom yes) (on_board yes)
      (property "Reference" "U" (at 30.48 -2.54 0)
        (effects (font (size 1.27 1.27) (thickness 0.15)) (justify left bottom))
      )
      (property "Value" "TPD8S009DSMR" (at 30.48 -12.7 0)
        (effects (font (size 1.27 1.27) (thickness 0.15)) (justify left bottom) hide)
      )
      (property "Footprint" "antmicro-footprints:R-PDSO-N15" (at 30.48 -7.62 0)
        (effects (font (size 1.27 1.27) (thickness 0.15)) (justify left bottom) hide)
      )
      (property "Datasheet" "https://www.ti.com/lit/ds/symlink/tpd8s009.pdf?ts=1679406571326&ref_url=https%253A%252F%252Fwww.ti.com%252Fproduct%252FTPD8S009%252Fpart-details%252FTPD8S009DSMR" (at 30.48 -10.16 0)
        (effects (font (size 1.27 1.27) (thickness 0.15)) (justify left bottom) hide)
      )
      (property "MPN" "TPD8S009DSMR" (at 30.48 -5.08 0)
        (effects (font (size 1.27 1.27) (thickness 0.15)) (justify left bottom))
      )
      (property "Manufacturer" "Texas Instruments" (at 30.48 -15.24 0)
        (effects (font (size 1.27 1.27) (thickness 0.15)) (justify left bottom) hide)
      )
      (property "Author" "Antmicro" (at 30.48 -17.78 0)
        (effects (font (size 1.27 1.27) (thickness 0.15)) (justify left bottom) hide)
      )
      (property "License" "Apache-2.0" (at 30.48 -20.32 0)
        (effects (font (size 1.27 1.27) (thickness 0.15)) (justify left bottom) hide)
      )
      (property "ki_keywords" "SMT, DIODE, SEMICONDUCTOR, TVS, ESD" (at 0 0 0)
        (effects (font (size 1.27 1.27)) hide)
      )
      (property "ki_description" "TVS diode array, 8 kV, R-PDSO-N15, 5.5 V, 0.8 pF" (at 0 0 0)
        (effects (font (size 1.27 1.27)) hide)
      )
      (symbol "TPD8S009DSMR_1_1"
        (rectangle (start 2.54 -20.32) (end 13.97 2.54)
          (stroke (width 0.254) (type default))
          (fill (type background))
        )
        (pin passive line (at 0 0 0) (length 2.54)
          (name "D0+" (effects (font (size 1.27 1.27))))
          (number "1" (effects (font (size 1.27 1.27))))
        )
        (pin passive line (at 0 -15.24 0) (length 2.54)
          (name "D3+" (effects (font (size 1.27 1.27))))
          (number "10" (effects (font (size 1.27 1.27))))
        )
        (pin passive line (at 16.51 -17.78 180) (length 2.54) hide
          (name "GND" (effects (font (size 1.27 1.27))))
          (number "11" (effects (font (size 1.27 1.27))))
        )
        (pin passive line (at 0 -17.78 0) (length 2.54)
          (name "D3-" (effects (font (size 1.27 1.27))))
          (number "12" (effects (font (size 1.27 1.27))))
        )
        (pin power_in line (at 16.51 0 180) (length 2.54)
          (name "VCC" (effects (font (size 1.27 1.27))))
          (number "13" (effects (font (size 1.27 1.27))))
        )
        (pin no_connect line (at 13.97 -15.24 180) (length 2.54) hide
          (name "NC" (effects (font (size 1.27 1.27))))
          (number "14" (effects (font (size 1.27 1.27))))
        )
        (pin passive line (at 16.51 0 180) (length 2.54) hide
          (name "VCC" (effects (font (size 1.27 1.27))))
          (number "15" (effects (font (size 1.27 1.27))))
        )
        (pin passive line (at 16.51 -17.78 180) (length 2.54)
          (name "GND" (effects (font (size 1.27 1.27))))
          (number "2" (effects (font (size 1.27 1.27))))
        )
        (pin passive line (at 0 -2.54 0) (length 2.54)
          (name "D0-" (effects (font (size 1.27 1.27))))
          (number "3" (effects (font (size 1.27 1.27))))
        )
        (pin passive line (at 0 -5.08 0) (length 2.54)
          (name "D1+" (effects (font (size 1.27 1.27))))
          (number "4" (effects (font (size 1.27 1.27))))
        )
        (pin passive line (at 16.51 -17.78 180) (length 2.54) hide
          (name "GND" (effects (font (size 1.27 1.27))))
          (number "5" (effects (font (size 1.27 1.27))))
        )
        (pin passive line (at 0 -7.62 0) (length 2.54)
          (name "D1-" (effects (font (size 1.27 1.27))))
          (number "6" (effects (font (size 1.27 1.27))))
        )
        (pin passive line (at 0 -10.16 0) (length 2.54)
          (name "D2+" (effects (font (size 1.27 1.27))))
          (number "7" (effects (font (size 1.27 1.27))))
        )
        (pin passive line (at 16.51 -17.78 180) (length 2.54) hide
          (name "GND" (effects (font (size 1.27 1.27))))
          (number "8" (effects (font (size 1.27 1.27))))
        )
        (pin passive line (at 16.51 -17.78 180) (length 2.54) hide
          (name "GND" (effects (font (size 1.27 1.27))))
          (number "8" (effects (font (size 1.27 1.27))))
        )
        (pin passive line (at 0 -12.7 0) (length 2.54)
          (name "D2-" (effects (font (size 1.27 1.27))))
          (number "9" (effects (font (size 1.27 1.27))))
        )
      )
    )
	(symbol "antmicroTestPoints:TP_0.75mm_SMD" (pin_names hide) (in_bom no) (on_board yes)
      (property "Reference" "TP" (at 10.16 -1.27 0)
        (effects (font (size 1.27 1.27) (thickness 0.15)) (justify left bottom))
      )
      (property "Value" "TP_0.75mm_SMD" (at 10.16 -3.81 0)
        (effects (font (size 1.27 1.27) (thickness 0.15)) (justify left bottom) hide)
      )
      (property "Footprint" "antmicro-footprints:TP_SMD_0.75mm" (at 10.16 -6.35 0)
        (effects (font (size 1.27 1.27) (thickness 0.15)) (justify left bottom) hide)
      )
      (property "Datasheet" "" (at 17.78 -12.7 0)
        (effects (font (size 1.27 1.27) (thickness 0.15)) (justify left bottom) hide)
      )
      (property "MPN" "" (at 10.795 -11.43 0)
        (effects (font (size 1.27 1.27) (thickness 0.15)) (justify left bottom) hide)
      )
      (property "Manufacturer" "" (at 10.795 -6.35 0)
        (effects (font (size 1.27 1.27) (thickness 0.15)) (justify left bottom) hide)
      )
      (property "Author" "Antmicro" (at 10.16 -8.89 0)
        (effects (font (size 1.27 1.27) (thickness 0.15)) (justify left bottom) hide)
      )
      (property "License" "Apache-2.0" (at 10.16 -11.43 0)
        (effects (font (size 1.27 1.27) (thickness 0.15)) (justify left bottom) hide)
      )
      (property "Public" "False" (at 10.16 -13.97 0)
        (effects (font (size 1.27 1.27)) (justify left bottom) hide)
      )
      (property "ki_keywords" "TESTPOINT" (at 0 0 0)
        (effects (font (size 1.27 1.27)) hide)
      )
      (property "ki_description" "SMT test point" (at 0 0 0)
        (effects (font (size 1.27 1.27)) hide)
      )
      (symbol "TP_0.75mm_SMD_1_1"
        (circle (center 3.175 0) (radius 0.635)
          (stroke (width 0.254) (type default))
          (fill (type none))
        )
        (pin passive line (at 0 0 0) (length 2.54)
          (name "1" (effects (font (size 1.27 1.27))))
          (number "1" (effects (font (size 1.27 1.27))))
        )
      )
    )
	(symbol "antmicroVideoConnectors:HDMI-A_Molex_471511001" (in_bom yes) (on_board yes)
      (property "Reference" "J" (at 45.72 -2.54 0)
        (effects (font (size 1.27 1.27) (thickness 0.15)) (justify left bottom))
      )
      (property "Value" "HDMI-A_Molex_471511001" (at 45.72 -5.08 0)
        (effects (font (size 1.27 1.27) (thickness 0.15)) (justify left bottom) hide)
      )
      (property "Footprint" "antmicro-footprints:HDMI-A_Receptacle_Molex_471511001" (at 45.72 -7.62 0)
        (effects (font (size 1.27 1.27) (thickness 0.15)) (justify left bottom) hide)
      )
      (property "Datasheet" "https://tools.molex.com/pdm_docs/sd/471511001_sd.pdf" (at 45.72 -10.16 0)
        (effects (font (size 1.27 1.27) (thickness 0.15)) (justify left bottom) hide)
      )
      (property "Manufacturer" "Molex" (at 45.72 -12.7 0)
        (effects (font (size 1.27 1.27) (thickness 0.15)) (justify left bottom) hide)
      )
      (property "MPN" "471511001" (at 45.72 -15.24 0)
        (effects (font (size 1.27 1.27) (thickness 0.15)) (justify left bottom))
      )
      (property "Author" "Antmicro" (at 45.72 -17.78 0)
        (effects (font (size 1.27 1.27) (thickness 0.15)) (justify left bottom) hide)
      )
      (property "License" "Apache-2.0" (at 45.72 -20.32 0)
        (effects (font (size 1.27 1.27) (thickness 0.15)) (justify left bottom) hide)
      )
      (property "ki_keywords" "HDMI, CONNECTOR, SMT, HORIZONTAL" (at 0 0 0)
        (effects (font (size 1.27 1.27)) hide)
      )
      (property "ki_description" "HDMI Receptacle Connector 19 Position Surface Mount, Right Angle; Through Hole" (at 0 0 0)
        (effects (font (size 1.27 1.27)) hide)
      )
      (symbol "HDMI-A_Molex_471511001_0_0"
        (polyline
          (pts
            (xy 22.098 0)
            (xy 22.098 1.524)
          )
          (stroke (width 0.635) (type default))
          (fill (type none))
        )
        (polyline
          (pts
            (xy 13.97 0)
            (xy 13.97 1.524)
            (xy 13.97 0.762)
            (xy 15.875 0.762)
            (xy 15.875 1.524)
            (xy 15.875 0)
          )
          (stroke (width 0.635) (type default))
          (fill (type none))
        )
        (polyline
          (pts
            (xy 16.637 1.524)
            (xy 18.288 1.524)
            (xy 18.542 1.27)
            (xy 18.542 0.254)
            (xy 18.288 0)
            (xy 16.637 0)
            (xy 16.637 0.762)
          )
          (stroke (width 0.635) (type default))
          (fill (type none))
        )
      )
      (symbol "HDMI-A_Molex_471511001_0_1"
        (polyline
          (pts
            (xy 10.16 -15.24)
            (xy 13.97 -15.24)
            (xy 15.875 -17.145)
            (xy 15.875 -28.575)
            (xy 13.97 -30.48)
            (xy 10.16 -30.48)
            (xy 10.16 -15.24)
          )
          (stroke (width 0.635) (type default))
          (fill (type none))
        )
        (polyline
          (pts
            (xy 12.065 -16.51)
            (xy 13.335 -16.51)
            (xy 13.97 -17.145)
            (xy 13.97 -28.575)
            (xy 13.335 -29.21)
            (xy 12.065 -29.21)
            (xy 12.065 -16.51)
          )
          (stroke (width 0.254) (type default))
          (fill (type outline))
        )
        (polyline
          (pts
            (xy 19.304 0)
            (xy 19.304 1.524)
            (xy 20.32 1.524)
            (xy 20.32 0)
            (xy 20.32 1.524)
            (xy 21.082 1.524)
            (xy 21.336 1.27)
            (xy 21.336 0)
          )
          (stroke (width 0.635) (type default))
          (fill (type none))
        )
      )
      (symbol "HDMI-A_Molex_471511001_1_1"
        (rectangle (start 2.54 2.54) (end 22.86 -53.34)
          (stroke (width 0.254) (type default))
          (fill (type background))
        )
        (pin bidirectional line (at 0 0 0) (length 2.54)
          (name "D2+" (effects (font (size 1.27 1.27))))
          (number "1" (effects (font (size 1.27 1.27))))
        )
        (pin bidirectional line (at 0 -22.86 0) (length 2.54)
          (name "CK+" (effects (font (size 1.27 1.27))))
          (number "10" (effects (font (size 1.27 1.27))))
        )
        (pin passive line (at 25.4 -45.72 180) (length 2.54)
          (name "CKS" (effects (font (size 1.27 1.27))))
          (number "11" (effects (font (size 1.27 1.27))))
        )
        (pin bidirectional line (at 0 -25.4 0) (length 2.54)
          (name "CK-" (effects (font (size 1.27 1.27))))
          (number "12" (effects (font (size 1.27 1.27))))
        )
        (pin bidirectional line (at 0 -38.1 0) (length 2.54)
          (name "CEC" (effects (font (size 1.27 1.27))))
          (number "13" (effects (font (size 1.27 1.27))))
        )
        (pin bidirectional line (at 0 -45.72 0) (length 2.54)
          (name "UTILITY/HEAC+" (effects (font (size 1.27 1.27))))
          (number "14" (effects (font (size 1.27 1.27))))
          (alternate "HEAC+" passive line)
          (alternate "UTILITY" passive line)
        )
        (pin bidirectional line (at 0 -30.48 0) (length 2.54)
          (name "SCL" (effects (font (size 1.27 1.27))))
          (number "15" (effects (font (size 1.27 1.27))))
        )
        (pin bidirectional line (at 0 -33.02 0) (length 2.54)
          (name "SDA" (effects (font (size 1.27 1.27))))
          (number "16" (effects (font (size 1.27 1.27))))
        )
        (pin power_in line (at 25.4 -48.26 180) (length 2.54)
          (name "GND" (effects (font (size 1.27 1.27))))
          (number "17" (effects (font (size 1.27 1.27))))
        )
        (pin power_in line (at 0 -50.8 0) (length 2.54)
          (name "+5V" (effects (font (size 1.27 1.27))))
          (number "18" (effects (font (size 1.27 1.27))))
        )
        (pin bidirectional line (at 0 -43.18 0) (length 2.54)
          (name "HPD/HEAC-" (effects (font (size 1.27 1.27))))
          (number "19" (effects (font (size 1.27 1.27))))
          (alternate "HEAC-" passive line)
          (alternate "HPD" passive line)
        )
        (pin passive line (at 25.4 -38.1 180) (length 2.54)
          (name "D2S" (effects (font (size 1.27 1.27))))
          (number "2" (effects (font (size 1.27 1.27))))
        )
        (pin bidirectional line (at 0 -2.54 0) (length 2.54)
          (name "D2-" (effects (font (size 1.27 1.27))))
          (number "3" (effects (font (size 1.27 1.27))))
        )
        (pin bidirectional line (at 0 -7.62 0) (length 2.54)
          (name "D1+" (effects (font (size 1.27 1.27))))
          (number "4" (effects (font (size 1.27 1.27))))
        )
        (pin passive line (at 25.4 -40.64 180) (length 2.54)
          (name "D1S" (effects (font (size 1.27 1.27))))
          (number "5" (effects (font (size 1.27 1.27))))
        )
        (pin bidirectional line (at 0 -10.16 0) (length 2.54)
          (name "D1-" (effects (font (size 1.27 1.27))))
          (number "6" (effects (font (size 1.27 1.27))))
        )
        (pin bidirectional line (at 0 -15.24 0) (length 2.54)
          (name "D0+" (effects (font (size 1.27 1.27))))
          (number "7" (effects (font (size 1.27 1.27))))
        )
        (pin passive line (at 25.4 -43.18 180) (length 2.54)
          (name "D0S" (effects (font (size 1.27 1.27))))
          (number "8" (effects (font (size 1.27 1.27))))
        )
        (pin bidirectional line (at 0 -17.78 0) (length 2.54)
          (name "D0-" (effects (font (size 1.27 1.27))))
          (number "9" (effects (font (size 1.27 1.27))))
        )
        (pin passive line (at 25.4 -50.8 180) (length 2.54)
          (name "SH" (effects (font (size 1.27 1.27))))
          (number "SH" (effects (font (size 1.27 1.27))))
        )
      )
    )
	(symbol "antmicropower:+3V3" (power) (pin_numbers hide) (pin_names hide) (in_bom yes) (on_board yes)
      (property "Reference" "#PWR" (at 15.24 0 0)
        (effects (font (size 1.27 1.27) (thickness 0.15)) (justify left bottom) hide)
      )
      (property "Value" "+3V3" (at -3.175 2.54 0)
        (effects (font (size 1.27 1.27) (thickness 0.15)) (justify left bottom))
      )
      (property "Footprint" "" (at 15.24 -7.62 0)
        (effects (font (size 1.27 1.27) (thickness 0.15)) (justify left bottom) hide)
      )
      (property "Datasheet" "" (at 15.24 -10.16 0)
        (effects (font (size 1.27 1.27) (thickness 0.15)) (justify left bottom) hide)
      )
      (property "Author" "Antmicro" (at 15.24 -2.54 0)
        (effects (font (size 1.27 1.27) (thickness 0.15)) (justify left bottom) hide)
      )
      (property "License" "Apache-2.0" (at 15.24 -5.08 0)
        (effects (font (size 1.27 1.27) (thickness 0.15)) (justify left bottom) hide)
      )
      (symbol "+3V3_0_1"
        (polyline
          (pts
            (xy 0 0)
            (xy 0 2.54)
          )
          (stroke (width 0) (type default))
          (fill (type none))
        )
        (polyline
          (pts
            (xy 0 2.54)
            (xy -0.762 1.27)
          )
          (stroke (width 0) (type default))
          (fill (type none))
        )
        (polyline
          (pts
            (xy 0 2.54)
            (xy 0.762 1.27)
          )
          (stroke (width 0) (type default))
          (fill (type none))
        )
      )
      (symbol "+3V3_1_1"
        (pin power_in line (at 0 0 90) (length 0) hide
          (name "+3V3" (effects (font (size 1.27 1.27))))
          (number "1" (effects (font (size 1.27 1.27))))
        )
      )
    )
	(symbol "antmicropower:+5V" (power) (pin_numbers hide) (pin_names hide) (in_bom yes) (on_board yes)
      (property "Reference" "#PWR" (at 15.24 -2.54 0)
        (effects (font (size 1.27 1.27) (thickness 0.15)) (justify left bottom) hide)
      )
      (property "Value" "+5V" (at 15.24 -5.08 0)
        (effects (font (size 1.27 1.27) (thickness 0.15)) (justify left bottom))
      )
      (property "Footprint" "" (at 15.24 -7.62 0)
        (effects (font (size 1.27 1.27) (thickness 0.15)) (justify left bottom) hide)
      )
      (property "Datasheet" "" (at 15.24 -10.16 0)
        (effects (font (size 1.27 1.27) (thickness 0.15)) (justify left bottom) hide)
      )
      (property "Author" "Antmicro" (at 15.24 -7.62 0)
        (effects (font (size 1.27 1.27) (thickness 0.15)) (justify left bottom) hide)
      )
      (property "License" "Apache-2.0" (at 15.24 -10.16 0)
        (effects (font (size 1.27 1.27) (thickness 0.15)) (justify left bottom) hide)
      )
      (symbol "+5V_1_1"
        (polyline
          (pts
            (xy -0.762 1.27)
            (xy 0 2.54)
          )
          (stroke (width 0) (type default))
          (fill (type background))
        )
        (polyline
          (pts
            (xy 0 0)
            (xy 0 2.54)
          )
          (stroke (width 0) (type default))
          (fill (type background))
        )
        (polyline
          (pts
            (xy 0 2.54)
            (xy 0.762 1.27)
          )
          (stroke (width 0) (type default))
          (fill (type background))
        )
        (pin power_in line (at 0 0 90) (length 0)
          (name "+5V" (effects (font (size 1.27 1.27))))
          (number "1" (effects (font (size 1.27 1.27))))
        )
      )
    )
	(symbol "antmicropower:GND" (power) (pin_numbers hide) (pin_names hide) (in_bom yes) (on_board yes)
      (property "Reference" "#PWR" (at 8.89 -2.54 0)
        (effects (font (size 1.27 1.27) (thickness 0.15)) (justify left bottom) hide)
      )
      (property "Value" "GND" (at 8.89 -5.08 0)
        (effects (font (size 1.27 1.27) (thickness 0.15)) (justify left bottom))
      )
      (property "Footprint" "" (at 8.89 -7.62 0)
        (effects (font (size 1.27 1.27) (thickness 0.15)) (justify left bottom) hide)
      )
      (property "Datasheet" "" (at 8.89 -12.7 0)
        (effects (font (size 1.27 1.27) (thickness 0.15)) (justify left bottom) hide)
      )
      (property "Author" "Antmicro" (at 8.89 -7.62 0)
        (effects (font (size 1.27 1.27) (thickness 0.15)) (justify left bottom) hide)
      )
      (property "License" "Apache-2.0" (at 8.89 -10.16 0)
        (effects (font (size 1.27 1.27) (thickness 0.15)) (justify left bottom) hide)
      )
      (symbol "GND_1_1"
        (polyline
          (pts
            (xy 0 0)
            (xy 0 -1.27)
            (xy 1.27 -1.27)
            (xy 0 -2.54)
            (xy -1.27 -1.27)
            (xy 0 -1.27)
          )
          (stroke (width 0) (type default))
          (fill (type none))
        )
        (pin power_in line (at 0 0 270) (length 0)
          (name "GND" (effects (font (size 1.27 1.27))))
          (number "1" (effects (font (size 1.27 1.27))))
        )
      )
    )
	(symbol "antmicropower:PWR_FLAG" (power) (pin_numbers hide) (pin_names (offset 0) hide) (in_bom yes) (on_board yes)
      (property "Reference" "#FLG" (at 0 1.905 0)
        (effects (font (size 1.27 1.27)) hide)
      )
      (property "Value" "PWR_FLAG" (at 0 3.81 0)
        (effects (font (size 1.27 1.27)))
      )
      (property "Footprint" "" (at 0 0 0)
        (effects (font (size 1.27 1.27)) hide)
      )
      (property "Datasheet" "" (at 0 0 0)
        (effects (font (size 1.27 1.27)) hide)
      )
      (symbol "PWR_FLAG_0_0"
        (pin power_out line (at 0 0 90) (length 0)
          (name "pwr" (effects (font (size 1.27 1.27))))
          (number "1" (effects (font (size 1.27 1.27))))
        )
      )
      (symbol "PWR_FLAG_0_1"
        (polyline
          (pts
            (xy 0 0)
            (xy 0 1.27)
            (xy -1.016 1.905)
            (xy 0 2.54)
            (xy 1.016 1.905)
            (xy 0 1.27)
          )
          (stroke (width 0) (type default))
          (fill (type none))
        )
      )
    )
)
